FILE_TYPE = MACRO_DRAWING;
SET COLOR_WIRE YELLOW;
SET COLOR_PROP ORANGE;
SET COLOR_DOT WHITE;
SET COLOR_ARC YELLOW;
SET COLOR_BODY GREEN;
SET COLOR_NOTE PURPLE;
SET PROP_DISPLAY VALUE;
SET PAGE_NUMBER P34;
FORCEADD OFFPAGE..2
(3775 2575);
FORCEPROP 2 LAST $XR0 65 
J 0
(3964 2575);
DISPLAY 0.638298 (3964 2575);
PAINT MONO (3964 2575);
FORCEPROP 2 LAST CDS_LIB standard
J 0
(3775 2575);
PAINT MONO (3775 2575);
DISPLAY INVISIBLE (3775 2575);
FORCEPROP 1 LAST OFFPAGE TRUE
J 0
(4100 2450);
DISPLAY 1.170213 (4100 2450);
PAINT GREEN (4100 2450);
DISPLAY INVISIBLE (4100 2450);
FORCEPROP 1 LAST COMMENT_BODY TRUE
J 0
(3730 2480);
DISPLAY 1.170213 (3730 2480);
PAINT GREEN (3730 2480);
DISPLAY INVISIBLE (3730 2480);
FORCEPROP 2 LAST PATH I100
J 0
(3950 2650);
DISPLAY 1.021277 (3950 2650);
DISPLAY INVISIBLE (3950 2650);
FORCEADD OFFPAGE..2
(3775 3825);
FORCEPROP 2 LAST $XR0 65 
J 0
(3964 3825);
DISPLAY 0.638298 (3964 3825);
PAINT MONO (3964 3825);
FORCEPROP 2 LAST CDS_LIB standard
J 0
(3775 3825);
PAINT MONO (3775 3825);
DISPLAY INVISIBLE (3775 3825);
FORCEPROP 1 LAST OFFPAGE TRUE
J 0
(4100 3700);
DISPLAY 1.170213 (4100 3700);
PAINT GREEN (4100 3700);
DISPLAY INVISIBLE (4100 3700);
FORCEPROP 1 LAST COMMENT_BODY TRUE
J 0
(3730 3730);
DISPLAY 1.170213 (3730 3730);
PAINT GREEN (3730 3730);
DISPLAY INVISIBLE (3730 3730);
FORCEPROP 2 LAST PATH I101
J 0
(3950 3900);
DISPLAY 1.021277 (3950 3900);
DISPLAY INVISIBLE (3950 3900);
FORCEADD SOCKET4677_AZIF0045P001C01CS..24
(900 2600);
FORCEPROP 1 LAST PART_NUMBER DGA^7000023
J 0
(-150 4050);
DISPLAY 0.723404 (-150 4050);
PAINT GREEN (-150 4050);
DISPLAY INVISIBLE (-150 4050);
FORCEPROP 2 LAST VALUE SOCKET4677_AZIF0045-P001C01CS
J 0
(-150 4175);
DISPLAY 1.021277 (-150 4175);
FORCEPROP 1 LAST MATERIAL IO
J 0
(-150 3975);
DISPLAY 0.723404 (-150 3975);
PAINT GREEN (-150 3975);
FORCEPROP 2 LAST PART_TYPE SMLF
J 0
(-150 4225);
DISPLAY 1.021277 (-150 4225);
FORCEPROP 1 LAST $LOCATION U2
J 0
(-150 4125);
DISPLAY 0.723404 (-150 4125);
PAINT GREEN (-150 4125);
FORCEPROP 0 LASTPIN (-300 1400) $PN E80
J 2
(-310 1410);
DISPLAY 0.680851 (-310 1410);
PAINT MONO (-310 1410);
FORCEPROP 0 LASTPIN (-300 1450) $PN F81
J 2
(-310 1460);
DISPLAY 0.680851 (-310 1460);
PAINT MONO (-310 1460);
FORCEPROP 0 LASTPIN (-300 1500) $PN G82
J 2
(-310 1510);
DISPLAY 0.680851 (-310 1510);
PAINT MONO (-310 1510);
FORCEPROP 0 LASTPIN (-300 1550) $PN K79
J 2
(-310 1560);
DISPLAY 0.680851 (-310 1560);
PAINT MONO (-310 1560);
FORCEPROP 0 LASTPIN (-300 1600) $PN J82
J 2
(-310 1610);
DISPLAY 0.680851 (-310 1610);
PAINT MONO (-310 1610);
FORCEPROP 0 LASTPIN (-300 1650) $PN L80
J 2
(-310 1660);
DISPLAY 0.680851 (-310 1660);
PAINT MONO (-310 1660);
FORCEPROP 0 LASTPIN (-300 1700) $PN AC80
J 2
(-310 1710);
DISPLAY 0.680851 (-310 1710);
PAINT MONO (-310 1710);
FORCEPROP 0 LASTPIN (-300 1750) $PN AD81
J 2
(-310 1760);
DISPLAY 0.680851 (-310 1760);
PAINT MONO (-310 1760);
FORCEPROP 0 LASTPIN (-300 1800) $PN AF79
J 2
(-310 1810);
DISPLAY 0.680851 (-310 1810);
PAINT MONO (-310 1810);
FORCEPROP 0 LASTPIN (-300 1850) $PN AE82
J 2
(-310 1860);
DISPLAY 0.680851 (-310 1860);
PAINT MONO (-310 1860);
FORCEPROP 0 LASTPIN (-300 1900) $PN AJ80
J 2
(-310 1910);
DISPLAY 0.680851 (-310 1910);
PAINT MONO (-310 1910);
FORCEPROP 0 LASTPIN (-300 1950) $PN AG82
J 2
(-310 1960);
DISPLAY 0.680851 (-310 1960);
PAINT MONO (-310 1960);
FORCEPROP 0 LASTPIN (-300 2000) $PN BA72
J 2
(-310 2010);
DISPLAY 0.680851 (-310 2010);
PAINT MONO (-310 2010);
FORCEPROP 0 LASTPIN (-300 2050) $PN AV73
J 2
(-310 2060);
DISPLAY 0.680851 (-310 2060);
PAINT MONO (-310 2060);
FORCEPROP 0 LASTPIN (-300 2100) $PN AY75
J 2
(-310 2110);
DISPLAY 0.680851 (-310 2110);
PAINT MONO (-310 2110);
FORCEPROP 0 LASTPIN (-300 2150) $PN BB75
J 2
(-310 2160);
DISPLAY 0.680851 (-310 2160);
PAINT MONO (-310 2160);
FORCEPROP 0 LASTPIN (-300 2200) $PN AW74
J 2
(-310 2210);
DISPLAY 0.680851 (-310 2210);
PAINT MONO (-310 2210);
FORCEPROP 0 LASTPIN (-300 2250) $PN BH75
J 2
(-310 2260);
DISPLAY 0.680851 (-310 2260);
PAINT MONO (-310 2260);
FORCEPROP 0 LASTPIN (-300 2300) $PN BJ76
J 2
(-310 2310);
DISPLAY 0.680851 (-310 2310);
PAINT MONO (-310 2310);
FORCEPROP 0 LASTPIN (-300 2350) $PN BL76
J 2
(-310 2360);
DISPLAY 0.680851 (-310 2360);
PAINT MONO (-310 2360);
FORCEPROP 0 LASTPIN (-300 2400) $PN BG74
J 2
(-310 2410);
DISPLAY 0.680851 (-310 2410);
PAINT MONO (-310 2410);
FORCEPROP 0 LASTPIN (-300 2450) $PN BN74
J 2
(-310 2460);
DISPLAY 0.680851 (-310 2460);
PAINT MONO (-310 2460);
FORCEPROP 0 LASTPIN (-300 2500) $PN BK73
J 2
(-310 2510);
DISPLAY 0.680851 (-310 2510);
PAINT MONO (-310 2510);
FORCEPROP 0 LASTPIN (-300 2550) $PN BD73
J 2
(-310 2560);
DISPLAY 0.680851 (-310 2560);
PAINT MONO (-310 2560);
FORCEPROP 0 LASTPIN (-300 2650) $PN G80
J 2
(-310 2660);
DISPLAY 0.680851 (-310 2660);
PAINT MONO (-310 2660);
FORCEPROP 0 LASTPIN (-300 2700) $PN E82
J 2
(-310 2710);
DISPLAY 0.680851 (-310 2710);
PAINT MONO (-310 2710);
FORCEPROP 0 LASTPIN (-300 2750) $PN H83
J 2
(-310 2760);
DISPLAY 0.680851 (-310 2760);
PAINT MONO (-310 2760);
FORCEPROP 0 LASTPIN (-300 2800) $PN M79
J 2
(-310 2810);
DISPLAY 0.680851 (-310 2810);
PAINT MONO (-310 2810);
FORCEPROP 0 LASTPIN (-300 2850) $PN L82
J 2
(-310 2860);
DISPLAY 0.680851 (-310 2860);
PAINT MONO (-310 2860);
FORCEPROP 0 LASTPIN (-300 2900) $PN K81
J 2
(-310 2910);
DISPLAY 0.680851 (-310 2910);
PAINT MONO (-310 2910);
FORCEPROP 0 LASTPIN (-300 2950) $PN AE80
J 2
(-310 2960);
DISPLAY 0.680851 (-310 2960);
PAINT MONO (-310 2960);
FORCEPROP 0 LASTPIN (-300 3000) $PN AC82
J 2
(-310 3010);
DISPLAY 0.680851 (-310 3010);
PAINT MONO (-310 3010);
FORCEPROP 0 LASTPIN (-300 3050) $PN AG80
J 2
(-310 3060);
DISPLAY 0.680851 (-310 3060);
PAINT MONO (-310 3060);
FORCEPROP 0 LASTPIN (-300 3100) $PN AF83
J 2
(-310 3110);
DISPLAY 0.680851 (-310 3110);
PAINT MONO (-310 3110);
FORCEPROP 0 LASTPIN (-300 3150) $PN AH81
J 2
(-310 3160);
DISPLAY 0.680851 (-310 3160);
PAINT MONO (-310 3160);
FORCEPROP 0 LASTPIN (-300 3200) $PN AJ82
J 2
(-310 3210);
DISPLAY 0.680851 (-310 3210);
PAINT MONO (-310 3210);
FORCEPROP 0 LASTPIN (-300 3250) $PN BB73
J 2
(-310 3260);
DISPLAY 0.680851 (-310 3260);
PAINT MONO (-310 3260);
FORCEPROP 0 LASTPIN (-300 3300) $PN AY73
J 2
(-310 3310);
DISPLAY 0.680851 (-310 3310);
PAINT MONO (-310 3310);
FORCEPROP 0 LASTPIN (-300 3350) $PN BA76
J 2
(-310 3360);
DISPLAY 0.680851 (-310 3360);
PAINT MONO (-310 3360);
FORCEPROP 0 LASTPIN (-300 3400) $PN BD75
J 2
(-310 3410);
DISPLAY 0.680851 (-310 3410);
PAINT MONO (-310 3410);
FORCEPROP 0 LASTPIN (-300 3450) $PN AV75
J 2
(-310 3460);
DISPLAY 0.680851 (-310 3460);
PAINT MONO (-310 3460);
FORCEPROP 0 LASTPIN (-300 3500) $PN BG76
J 2
(-310 3510);
DISPLAY 0.680851 (-310 3510);
PAINT MONO (-310 3510);
FORCEPROP 0 LASTPIN (-300 3550) $PN BK77
J 2
(-310 3560);
DISPLAY 0.680851 (-310 3560);
PAINT MONO (-310 3560);
FORCEPROP 0 LASTPIN (-300 3600) $PN BN76
J 2
(-310 3610);
DISPLAY 0.680851 (-310 3610);
PAINT MONO (-310 3610);
FORCEPROP 0 LASTPIN (-300 3650) $PN BJ74
J 2
(-310 3660);
DISPLAY 0.680851 (-310 3660);
PAINT MONO (-310 3660);
FORCEPROP 0 LASTPIN (-300 3700) $PN BM75
J 2
(-310 3710);
DISPLAY 0.680851 (-310 3710);
PAINT MONO (-310 3710);
FORCEPROP 0 LASTPIN (-300 3750) $PN BL74
J 2
(-310 3760);
DISPLAY 0.680851 (-310 3760);
PAINT MONO (-310 3760);
FORCEPROP 0 LASTPIN (-300 3800) $PN BC74
J 2
(-310 3810);
DISPLAY 0.680851 (-310 3810);
PAINT MONO (-310 3810);
FORCEPROP 0 LASTPIN (2100 1400) $PN B85
J 0
(2110 1410);
DISPLAY 0.680851 (2110 1410);
PAINT MONO (2110 1410);
FORCEPROP 0 LASTPIN (2100 1450) $PN E84
J 0
(2110 1460);
DISPLAY 0.680851 (2110 1460);
PAINT MONO (2110 1460);
FORCEPROP 0 LASTPIN (2100 1500) $PN D87
J 0
(2110 1510);
DISPLAY 0.680851 (2110 1510);
PAINT MONO (2110 1510);
FORCEPROP 0 LASTPIN (2100 1550) $PN F87
J 0
(2110 1560);
DISPLAY 0.680851 (2110 1560);
PAINT MONO (2110 1560);
FORCEPROP 0 LASTPIN (2100 1600) $PN H85
J 0
(2110 1610);
DISPLAY 0.680851 (2110 1610);
PAINT MONO (2110 1610);
FORCEPROP 0 LASTPIN (2100 1650) $PN P81
J 0
(2110 1660);
DISPLAY 0.680851 (2110 1660);
PAINT MONO (2110 1660);
FORCEPROP 0 LASTPIN (2100 1700) $PN R82
J 0
(2110 1710);
DISPLAY 0.680851 (2110 1710);
PAINT MONO (2110 1710);
FORCEPROP 0 LASTPIN (2100 1750) $PN U80
J 0
(2110 1760);
DISPLAY 0.680851 (2110 1760);
PAINT MONO (2110 1760);
FORCEPROP 0 LASTPIN (2100 1800) $PN V83
J 0
(2110 1810);
DISPLAY 0.680851 (2110 1810);
PAINT MONO (2110 1810);
FORCEPROP 0 LASTPIN (2100 1850) $PN Y81
J 0
(2110 1860);
DISPLAY 0.680851 (2110 1860);
PAINT MONO (2110 1860);
FORCEPROP 0 LASTPIN (2100 1900) $PN AW78
J 0
(2110 1910);
DISPLAY 0.680851 (2110 1910);
PAINT MONO (2110 1910);
FORCEPROP 0 LASTPIN (2100 1950) $PN AU78
J 0
(2110 1960);
DISPLAY 0.680851 (2110 1960);
PAINT MONO (2110 1960);
FORCEPROP 0 LASTPIN (2100 2000) $PN AM81
J 0
(2110 2010);
DISPLAY 0.680851 (2110 2010);
PAINT MONO (2110 2010);
FORCEPROP 0 LASTPIN (2100 2050) $PN AN82
J 0
(2110 2060);
DISPLAY 0.680851 (2110 2060);
PAINT MONO (2110 2060);
FORCEPROP 0 LASTPIN (2100 2100) $PN AR80
J 0
(2110 2110);
DISPLAY 0.680851 (2110 2110);
PAINT MONO (2110 2110);
FORCEPROP 0 LASTPIN (2100 2150) $PN AT83
J 0
(2110 2160);
DISPLAY 0.680851 (2110 2160);
PAINT MONO (2110 2160);
FORCEPROP 0 LASTPIN (2100 2200) $PN AV81
J 0
(2110 2210);
DISPLAY 0.680851 (2110 2210);
PAINT MONO (2110 2210);
FORCEPROP 0 LASTPIN (2100 2250) $PN BA80
J 0
(2110 2260);
DISPLAY 0.680851 (2110 2260);
PAINT MONO (2110 2260);
FORCEPROP 0 LASTPIN (2100 2300) $PN BC82
J 0
(2110 2310);
DISPLAY 0.680851 (2110 2310);
PAINT MONO (2110 2310);
FORCEPROP 0 LASTPIN (2100 2350) $PN BE82
J 0
(2110 2360);
DISPLAY 0.680851 (2110 2360);
PAINT MONO (2110 2360);
FORCEPROP 0 LASTPIN (2100 2400) $PN BD79
J 0
(2110 2410);
DISPLAY 0.680851 (2110 2410);
PAINT MONO (2110 2410);
FORCEPROP 0 LASTPIN (2100 2450) $PN BF81
J 0
(2110 2460);
DISPLAY 0.680851 (2110 2460);
PAINT MONO (2110 2460);
FORCEPROP 0 LASTPIN (2100 2500) $PN BG80
J 0
(2110 2510);
DISPLAY 0.680851 (2110 2510);
PAINT MONO (2110 2510);
FORCEPROP 0 LASTPIN (2100 2550) $PN BM71
J 0
(2110 2560);
DISPLAY 0.680851 (2110 2560);
PAINT MONO (2110 2560);
FORCEPROP 0 LASTPIN (2100 2650) $PN D85
J 0
(2110 2660);
DISPLAY 0.680851 (2110 2660);
PAINT MONO (2110 2660);
FORCEPROP 0 LASTPIN (2100 2700) $PN F85
J 0
(2110 2710);
DISPLAY 0.680851 (2110 2710);
PAINT MONO (2110 2710);
FORCEPROP 0 LASTPIN (2100 2750) $PN E88
J 0
(2110 2760);
DISPLAY 0.680851 (2110 2760);
PAINT MONO (2110 2760);
FORCEPROP 0 LASTPIN (2100 2800) $PN H87
J 0
(2110 2810);
DISPLAY 0.680851 (2110 2810);
PAINT MONO (2110 2810);
FORCEPROP 0 LASTPIN (2100 2850) $PN G86
J 0
(2110 2860);
DISPLAY 0.680851 (2110 2860);
PAINT MONO (2110 2860);
FORCEPROP 0 LASTPIN (2100 2900) $PN T81
J 0
(2110 2910);
DISPLAY 0.680851 (2110 2910);
PAINT MONO (2110 2910);
FORCEPROP 0 LASTPIN (2100 2950) $PN P83
J 0
(2110 2960);
DISPLAY 0.680851 (2110 2960);
PAINT MONO (2110 2960);
FORCEPROP 0 LASTPIN (2100 3000) $PN V81
J 0
(2110 3010);
DISPLAY 0.680851 (2110 3010);
PAINT MONO (2110 3010);
FORCEPROP 0 LASTPIN (2100 3050) $PN Y83
J 0
(2110 3060);
DISPLAY 0.680851 (2110 3060);
PAINT MONO (2110 3060);
FORCEPROP 0 LASTPIN (2100 3100) $PN W82
J 0
(2110 3110);
DISPLAY 0.680851 (2110 3110);
PAINT MONO (2110 3110);
FORCEPROP 0 LASTPIN (2100 3150) $PN BA78
J 0
(2110 3160);
DISPLAY 0.680851 (2110 3160);
PAINT MONO (2110 3160);
FORCEPROP 0 LASTPIN (2100 3200) $PN AV79
J 0
(2110 3210);
DISPLAY 0.680851 (2110 3210);
PAINT MONO (2110 3210);
FORCEPROP 0 LASTPIN (2100 3250) $PN AP81
J 0
(2110 3260);
DISPLAY 0.680851 (2110 3260);
PAINT MONO (2110 3260);
FORCEPROP 0 LASTPIN (2100 3300) $PN AM83
J 0
(2110 3310);
DISPLAY 0.680851 (2110 3310);
PAINT MONO (2110 3310);
FORCEPROP 0 LASTPIN (2100 3350) $PN AT81
J 0
(2110 3360);
DISPLAY 0.680851 (2110 3360);
PAINT MONO (2110 3360);
FORCEPROP 0 LASTPIN (2100 3400) $PN AV83
J 0
(2110 3410);
DISPLAY 0.680851 (2110 3410);
PAINT MONO (2110 3410);
FORCEPROP 0 LASTPIN (2100 3450) $PN AU82
J 0
(2110 3460);
DISPLAY 0.680851 (2110 3460);
PAINT MONO (2110 3460);
FORCEPROP 0 LASTPIN (2100 3500) $PN BB81
J 0
(2110 3510);
DISPLAY 0.680851 (2110 3510);
PAINT MONO (2110 3510);
FORCEPROP 0 LASTPIN (2100 3550) $PN BA82
J 0
(2110 3560);
DISPLAY 0.680851 (2110 3560);
PAINT MONO (2110 3560);
FORCEPROP 0 LASTPIN (2100 3600) $PN BD83
J 0
(2110 3610);
DISPLAY 0.680851 (2110 3610);
PAINT MONO (2110 3610);
FORCEPROP 0 LASTPIN (2100 3650) $PN BC80
J 0
(2110 3660);
DISPLAY 0.680851 (2110 3660);
PAINT MONO (2110 3660);
FORCEPROP 0 LASTPIN (2100 3700) $PN BG82
J 0
(2110 3710);
DISPLAY 0.680851 (2110 3710);
PAINT MONO (2110 3710);
FORCEPROP 0 LASTPIN (2100 3750) $PN BE80
J 0
(2110 3760);
DISPLAY 0.680851 (2110 3760);
PAINT MONO (2110 3760);
FORCEPROP 0 LASTPIN (2100 3800) $PN BN72
J 0
(2110 3810);
DISPLAY 0.680851 (2110 3810);
PAINT MONO (2110 3810);
FORCEPROP 1 LAST CDS_LMAN_SYM_OUTLINE -1050,1350,1050,-1350
J 0
(900 2600);
DISPLAY 0.468085 (900 2600);
PAINT GREEN (900 2600);
DISPLAY INVISIBLE (900 2600);
FORCEPROP 1 LAST NEEDS_NO_SIZE TRUE
J 0
(900 2600);
DISPLAY 0.723404 (900 2600);
PAINT GREEN (900 2600);
DISPLAY INVISIBLE (900 2600);
FORCEPROP 2 LAST CDS_LIB pure_quanta
J 0
(900 2600);
DISPLAY INVISIBLE (900 2600);
FORCEPROP 2 LAST CDS_LOCATION U2
J 0
(-150 4275);
DISPLAY 1.021277 (-150 4275);
DISPLAY INVISIBLE (-150 4275);
FORCEPROP 0 LAST $SEC 24
J 0
(-150 4275);
DISPLAY 0.680851 (-150 4275);
PAINT MONO (-150 4275);
DISPLAY INVISIBLE (-150 4275);
FORCEPROP 2 LAST CDS_SEC 24
J 0
(-150 4275);
DISPLAY 1.021277 (-150 4275);
DISPLAY INVISIBLE (-150 4275);
FORCEPROP 1 LAST PATH I102
J 0
(900 2600);
DISPLAY 0.723404 (900 2600);
PAINT GREEN (900 2600);
DISPLAY INVISIBLE (900 2600);
FORCEADD TAP..1
R 2
(-1000 2700);
FORCEPROP 3 LASTPIN (-950 2700) SIG_NAME UPI_CPU1_CPU0_P2P2_DN<22>
J 0
(-940 2710);
DISPLAY 0.659574 (-940 2710);
PAINT MONO (-940 2710);
DISPLAY INVISIBLE (-940 2710);
FORCEPROP 1 LASTPIN (-950 2700) BN 22
J 2
(-938 2708);
DISPLAY 0.680851 (-938 2708);
PAINT GREEN (-938 2708);
FORCEPROP 2 LAST CDS_LIB standard
J 0
(-1000 2700);
DISPLAY INVISIBLE (-1000 2700);
FORCEPROP 1 LAST BODY_TYPE PLUMBING
J 2
(-1000 2750);
DISPLAY 0.872340 (-1000 2750);
PAINT GREEN (-1000 2750);
DISPLAY INVISIBLE (-1000 2750);
FORCEPROP 1 LAST HDL_TAP TRUE
J 2
(-1325 2575);
DISPLAY 0.872340 (-1325 2575);
DISPLAY INVISIBLE (-1325 2575);
FORCEPROP 1 LAST PATH I103
J 2
(-998 2700);
DISPLAY 0.872340 (-998 2700);
PAINT GREEN (-998 2700);
DISPLAY INVISIBLE (-998 2700);
FORCEADD TAP..1
R 2
(-1000 3000);
FORCEPROP 3 LASTPIN (-950 3000) SIG_NAME UPI_CPU1_CPU0_P2P2_DN<16>
J 0
(-940 3010);
DISPLAY 0.659574 (-940 3010);
PAINT MONO (-940 3010);
DISPLAY INVISIBLE (-940 3010);
FORCEPROP 1 LASTPIN (-950 3000) BN 16
J 2
(-938 3008);
DISPLAY 0.680851 (-938 3008);
PAINT GREEN (-938 3008);
FORCEPROP 2 LAST CDS_LIB standard
J 0
(-1000 3000);
DISPLAY INVISIBLE (-1000 3000);
FORCEPROP 1 LAST BODY_TYPE PLUMBING
J 2
(-1000 3050);
DISPLAY 0.872340 (-1000 3050);
PAINT GREEN (-1000 3050);
DISPLAY INVISIBLE (-1000 3050);
FORCEPROP 1 LAST HDL_TAP TRUE
J 2
(-1325 2875);
DISPLAY 0.872340 (-1325 2875);
DISPLAY INVISIBLE (-1325 2875);
FORCEPROP 1 LAST PATH I105
J 2
(-998 3000);
DISPLAY 0.872340 (-998 3000);
PAINT GREEN (-998 3000);
DISPLAY INVISIBLE (-998 3000);
FORCEADD TAP..1
R 2
(-1000 3250);
FORCEPROP 3 LASTPIN (-950 3250) SIG_NAME UPI_CPU1_CPU0_P2P2_DN<11>
J 0
(-940 3260);
DISPLAY 0.659574 (-940 3260);
PAINT MONO (-940 3260);
DISPLAY INVISIBLE (-940 3260);
FORCEPROP 1 LASTPIN (-950 3250) BN 11
J 2
(-938 3258);
DISPLAY 0.680851 (-938 3258);
PAINT GREEN (-938 3258);
FORCEPROP 2 LAST CDS_LIB standard
J 0
(-1000 3250);
DISPLAY INVISIBLE (-1000 3250);
FORCEPROP 1 LAST BODY_TYPE PLUMBING
J 2
(-1000 3300);
DISPLAY 0.872340 (-1000 3300);
PAINT GREEN (-1000 3300);
DISPLAY INVISIBLE (-1000 3300);
FORCEPROP 1 LAST HDL_TAP TRUE
J 2
(-1325 3125);
DISPLAY 0.872340 (-1325 3125);
DISPLAY INVISIBLE (-1325 3125);
FORCEPROP 1 LAST PATH I106
J 2
(-998 3250);
DISPLAY 0.872340 (-998 3250);
PAINT GREEN (-998 3250);
DISPLAY INVISIBLE (-998 3250);
FORCEADD TAP..1
R 2
(-1000 3200);
FORCEPROP 3 LASTPIN (-950 3200) SIG_NAME UPI_CPU1_CPU0_P2P2_DN<12>
J 0
(-940 3210);
DISPLAY 0.659574 (-940 3210);
PAINT MONO (-940 3210);
DISPLAY INVISIBLE (-940 3210);
FORCEPROP 1 LASTPIN (-950 3200) BN 12
J 2
(-938 3208);
DISPLAY 0.680851 (-938 3208);
PAINT GREEN (-938 3208);
FORCEPROP 2 LAST CDS_LIB standard
J 0
(-1000 3200);
DISPLAY INVISIBLE (-1000 3200);
FORCEPROP 1 LAST BODY_TYPE PLUMBING
J 2
(-1000 3250);
DISPLAY 0.872340 (-1000 3250);
PAINT GREEN (-1000 3250);
DISPLAY INVISIBLE (-1000 3250);
FORCEPROP 1 LAST HDL_TAP TRUE
J 2
(-1325 3075);
DISPLAY 0.872340 (-1325 3075);
DISPLAY INVISIBLE (-1325 3075);
FORCEPROP 1 LAST PATH I107
J 2
(-998 3200);
DISPLAY 0.872340 (-998 3200);
PAINT GREEN (-998 3200);
DISPLAY INVISIBLE (-998 3200);
FORCEADD TAP..1
R 2
(-1000 3050);
FORCEPROP 3 LASTPIN (-950 3050) SIG_NAME UPI_CPU1_CPU0_P2P2_DN<15>
J 0
(-940 3060);
DISPLAY 0.659574 (-940 3060);
PAINT MONO (-940 3060);
DISPLAY INVISIBLE (-940 3060);
FORCEPROP 1 LASTPIN (-950 3050) BN 15
J 2
(-938 3058);
DISPLAY 0.680851 (-938 3058);
PAINT GREEN (-938 3058);
FORCEPROP 2 LAST CDS_LIB standard
J 0
(-1000 3050);
DISPLAY INVISIBLE (-1000 3050);
FORCEPROP 1 LAST BODY_TYPE PLUMBING
J 2
(-1000 3100);
DISPLAY 0.872340 (-1000 3100);
PAINT GREEN (-1000 3100);
DISPLAY INVISIBLE (-1000 3100);
FORCEPROP 1 LAST HDL_TAP TRUE
J 2
(-1325 2925);
DISPLAY 0.872340 (-1325 2925);
DISPLAY INVISIBLE (-1325 2925);
FORCEPROP 1 LAST PATH I108
J 2
(-998 3050);
DISPLAY 0.872340 (-998 3050);
PAINT GREEN (-998 3050);
DISPLAY INVISIBLE (-998 3050);
FORCEADD TAP..1
R 2
(-1000 3100);
FORCEPROP 3 LASTPIN (-950 3100) SIG_NAME UPI_CPU1_CPU0_P2P2_DN<14>
J 0
(-940 3110);
DISPLAY 0.659574 (-940 3110);
PAINT MONO (-940 3110);
DISPLAY INVISIBLE (-940 3110);
FORCEPROP 1 LASTPIN (-950 3100) BN 14
J 2
(-938 3108);
DISPLAY 0.680851 (-938 3108);
PAINT GREEN (-938 3108);
FORCEPROP 2 LAST CDS_LIB standard
J 0
(-1000 3100);
DISPLAY INVISIBLE (-1000 3100);
FORCEPROP 1 LAST BODY_TYPE PLUMBING
J 2
(-1000 3150);
DISPLAY 0.872340 (-1000 3150);
PAINT GREEN (-1000 3150);
DISPLAY INVISIBLE (-1000 3150);
FORCEPROP 1 LAST HDL_TAP TRUE
J 2
(-1325 2975);
DISPLAY 0.872340 (-1325 2975);
DISPLAY INVISIBLE (-1325 2975);
FORCEPROP 1 LAST PATH I109
J 2
(-998 3100);
DISPLAY 0.872340 (-998 3100);
PAINT GREEN (-998 3100);
DISPLAY INVISIBLE (-998 3100);
FORCEADD TAP..1
R 2
(-1000 3400);
FORCEPROP 3 LASTPIN (-950 3400) SIG_NAME UPI_CPU1_CPU0_P2P2_DN<8>
J 0
(-940 3410);
DISPLAY 0.659574 (-940 3410);
PAINT MONO (-940 3410);
DISPLAY INVISIBLE (-940 3410);
FORCEPROP 1 LASTPIN (-950 3400) BN 8
J 2
(-938 3408);
DISPLAY 0.680851 (-938 3408);
PAINT GREEN (-938 3408);
FORCEPROP 2 LAST CDS_LIB standard
J 0
(-1000 3400);
DISPLAY INVISIBLE (-1000 3400);
FORCEPROP 1 LAST BODY_TYPE PLUMBING
J 2
(-1000 3450);
DISPLAY 0.872340 (-1000 3450);
PAINT GREEN (-1000 3450);
DISPLAY INVISIBLE (-1000 3450);
FORCEPROP 1 LAST HDL_TAP TRUE
J 2
(-1325 3275);
DISPLAY 0.872340 (-1325 3275);
DISPLAY INVISIBLE (-1325 3275);
FORCEPROP 1 LAST PATH I110
J 2
(-998 3400);
DISPLAY 0.872340 (-998 3400);
PAINT GREEN (-998 3400);
DISPLAY INVISIBLE (-998 3400);
FORCEADD TAP..1
R 2
(-1000 3450);
FORCEPROP 3 LASTPIN (-950 3450) SIG_NAME UPI_CPU1_CPU0_P2P2_DN<7>
J 0
(-940 3460);
DISPLAY 0.659574 (-940 3460);
PAINT MONO (-940 3460);
DISPLAY INVISIBLE (-940 3460);
FORCEPROP 1 LASTPIN (-950 3450) BN 7
J 2
(-938 3458);
DISPLAY 0.680851 (-938 3458);
PAINT GREEN (-938 3458);
FORCEPROP 2 LAST CDS_LIB standard
J 0
(-1000 3450);
PAINT MONO (-1000 3450);
DISPLAY INVISIBLE (-1000 3450);
FORCEPROP 1 LAST BODY_TYPE PLUMBING
J 2
(-1000 3500);
DISPLAY 0.872340 (-1000 3500);
PAINT GREEN (-1000 3500);
DISPLAY INVISIBLE (-1000 3500);
FORCEPROP 1 LAST HDL_TAP TRUE
J 2
(-1325 3325);
DISPLAY 0.872340 (-1325 3325);
DISPLAY INVISIBLE (-1325 3325);
FORCEPROP 1 LAST PATH I111
J 2
(-998 3450);
DISPLAY 0.872340 (-998 3450);
PAINT GREEN (-998 3450);
DISPLAY INVISIBLE (-998 3450);
FORCEADD TAP..1
R 2
(-1000 3600);
FORCEPROP 3 LASTPIN (-950 3600) SIG_NAME UPI_CPU1_CPU0_P2P2_DN<4>
J 0
(-940 3610);
DISPLAY 0.659574 (-940 3610);
PAINT MONO (-940 3610);
DISPLAY INVISIBLE (-940 3610);
FORCEPROP 1 LASTPIN (-950 3600) BN 4
J 2
(-938 3608);
DISPLAY 0.680851 (-938 3608);
PAINT GREEN (-938 3608);
FORCEPROP 2 LAST CDS_LIB standard
J 0
(-1000 3600);
PAINT MONO (-1000 3600);
DISPLAY INVISIBLE (-1000 3600);
FORCEPROP 1 LAST BODY_TYPE PLUMBING
J 2
(-1000 3650);
DISPLAY 0.872340 (-1000 3650);
PAINT GREEN (-1000 3650);
DISPLAY INVISIBLE (-1000 3650);
FORCEPROP 1 LAST HDL_TAP TRUE
J 2
(-1325 3475);
DISPLAY 0.872340 (-1325 3475);
DISPLAY INVISIBLE (-1325 3475);
FORCEPROP 1 LAST PATH I112
J 2
(-998 3600);
DISPLAY 0.872340 (-998 3600);
PAINT GREEN (-998 3600);
DISPLAY INVISIBLE (-998 3600);
FORCEADD TAP..1
R 2
(-1000 3650);
FORCEPROP 3 LASTPIN (-950 3650) SIG_NAME UPI_CPU1_CPU0_P2P2_DN<3>
J 0
(-940 3660);
DISPLAY 0.659574 (-940 3660);
PAINT MONO (-940 3660);
DISPLAY INVISIBLE (-940 3660);
FORCEPROP 1 LASTPIN (-950 3650) BN 3
J 2
(-938 3658);
DISPLAY 0.680851 (-938 3658);
PAINT GREEN (-938 3658);
FORCEPROP 2 LAST CDS_LIB standard
J 0
(-1000 3650);
PAINT MONO (-1000 3650);
DISPLAY INVISIBLE (-1000 3650);
FORCEPROP 1 LAST BODY_TYPE PLUMBING
J 2
(-1000 3700);
DISPLAY 0.872340 (-1000 3700);
PAINT GREEN (-1000 3700);
DISPLAY INVISIBLE (-1000 3700);
FORCEPROP 1 LAST HDL_TAP TRUE
J 2
(-1325 3525);
DISPLAY 0.872340 (-1325 3525);
DISPLAY INVISIBLE (-1325 3525);
FORCEPROP 1 LAST PATH I113
J 2
(-998 3650);
DISPLAY 0.872340 (-998 3650);
PAINT GREEN (-998 3650);
DISPLAY INVISIBLE (-998 3650);
FORCEADD TAP..1
R 2
(-1000 3700);
FORCEPROP 3 LASTPIN (-950 3700) SIG_NAME UPI_CPU1_CPU0_P2P2_DN<2>
J 0
(-940 3710);
DISPLAY 0.659574 (-940 3710);
PAINT MONO (-940 3710);
DISPLAY INVISIBLE (-940 3710);
FORCEPROP 1 LASTPIN (-950 3700) BN 2
J 2
(-938 3708);
DISPLAY 0.680851 (-938 3708);
PAINT GREEN (-938 3708);
FORCEPROP 2 LAST CDS_LIB standard
J 0
(-1000 3700);
PAINT MONO (-1000 3700);
DISPLAY INVISIBLE (-1000 3700);
FORCEPROP 1 LAST BODY_TYPE PLUMBING
J 2
(-1000 3750);
DISPLAY 0.872340 (-1000 3750);
PAINT GREEN (-1000 3750);
DISPLAY INVISIBLE (-1000 3750);
FORCEPROP 1 LAST HDL_TAP TRUE
J 2
(-1325 3575);
DISPLAY 0.872340 (-1325 3575);
DISPLAY INVISIBLE (-1325 3575);
FORCEPROP 1 LAST PATH I114
J 2
(-998 3700);
DISPLAY 0.872340 (-998 3700);
PAINT GREEN (-998 3700);
DISPLAY INVISIBLE (-998 3700);
FORCEADD TAP..1
R 2
(-1000 3800);
FORCEPROP 3 LASTPIN (-950 3800) SIG_NAME UPI_CPU1_CPU0_P2P2_DN<0>
J 0
(-940 3810);
DISPLAY 0.659574 (-940 3810);
PAINT MONO (-940 3810);
DISPLAY INVISIBLE (-940 3810);
FORCEPROP 1 LASTPIN (-950 3800) BN 0
J 2
(-938 3808);
DISPLAY 0.680851 (-938 3808);
PAINT GREEN (-938 3808);
FORCEPROP 2 LAST CDS_LIB standard
J 0
(-1000 3800);
PAINT MONO (-1000 3800);
DISPLAY INVISIBLE (-1000 3800);
FORCEPROP 1 LAST BODY_TYPE PLUMBING
J 2
(-1000 3850);
DISPLAY 0.872340 (-1000 3850);
PAINT GREEN (-1000 3850);
DISPLAY INVISIBLE (-1000 3850);
FORCEPROP 1 LAST HDL_TAP TRUE
J 2
(-1325 3675);
DISPLAY 0.872340 (-1325 3675);
DISPLAY INVISIBLE (-1325 3675);
FORCEPROP 1 LAST PATH I115
J 2
(-998 3800);
DISPLAY 0.872340 (-998 3800);
PAINT GREEN (-998 3800);
DISPLAY INVISIBLE (-998 3800);
FORCEADD TAP..1
R 2
(-800 1450);
FORCEPROP 3 LASTPIN (-750 1450) SIG_NAME UPI_CPU1_CPU0_P2P2_DP<22>
J 0
(-740 1460);
DISPLAY 0.659574 (-740 1460);
PAINT MONO (-740 1460);
DISPLAY INVISIBLE (-740 1460);
FORCEPROP 1 LASTPIN (-750 1450) BN 22
J 2
(-738 1458);
DISPLAY 0.680851 (-738 1458);
PAINT GREEN (-738 1458);
FORCEPROP 2 LAST CDS_LIB standard
J 0
(-800 1450);
DISPLAY INVISIBLE (-800 1450);
FORCEPROP 1 LAST BODY_TYPE PLUMBING
J 2
(-800 1500);
DISPLAY 0.872340 (-800 1500);
PAINT GREEN (-800 1500);
DISPLAY INVISIBLE (-800 1500);
FORCEPROP 1 LAST HDL_TAP TRUE
J 2
(-1125 1325);
DISPLAY 0.872340 (-1125 1325);
DISPLAY INVISIBLE (-1125 1325);
FORCEPROP 1 LAST PATH I116
J 2
(-798 1450);
DISPLAY 0.872340 (-798 1450);
PAINT GREEN (-798 1450);
DISPLAY INVISIBLE (-798 1450);
FORCEADD TAP..1
R 2
(-800 1750);
FORCEPROP 3 LASTPIN (-750 1750) SIG_NAME UPI_CPU1_CPU0_P2P2_DP<16>
J 0
(-740 1760);
DISPLAY 0.659574 (-740 1760);
PAINT MONO (-740 1760);
DISPLAY INVISIBLE (-740 1760);
FORCEPROP 1 LASTPIN (-750 1750) BN 16
J 2
(-738 1758);
DISPLAY 0.680851 (-738 1758);
PAINT GREEN (-738 1758);
FORCEPROP 2 LAST CDS_LIB standard
J 0
(-800 1750);
DISPLAY INVISIBLE (-800 1750);
FORCEPROP 1 LAST BODY_TYPE PLUMBING
J 2
(-800 1800);
DISPLAY 0.872340 (-800 1800);
PAINT GREEN (-800 1800);
DISPLAY INVISIBLE (-800 1800);
FORCEPROP 1 LAST HDL_TAP TRUE
J 2
(-1125 1625);
DISPLAY 0.872340 (-1125 1625);
DISPLAY INVISIBLE (-1125 1625);
FORCEPROP 1 LAST PATH I118
J 2
(-798 1750);
DISPLAY 0.872340 (-798 1750);
PAINT GREEN (-798 1750);
DISPLAY INVISIBLE (-798 1750);
FORCEADD TAP..1
R 2
(-800 2000);
FORCEPROP 3 LASTPIN (-750 2000) SIG_NAME UPI_CPU1_CPU0_P2P2_DP<11>
J 0
(-740 2010);
DISPLAY 0.659574 (-740 2010);
PAINT MONO (-740 2010);
DISPLAY INVISIBLE (-740 2010);
FORCEPROP 1 LASTPIN (-750 2000) BN 11
J 2
(-738 2008);
DISPLAY 0.680851 (-738 2008);
PAINT GREEN (-738 2008);
FORCEPROP 2 LAST CDS_LIB standard
J 0
(-800 2000);
DISPLAY INVISIBLE (-800 2000);
FORCEPROP 1 LAST BODY_TYPE PLUMBING
J 2
(-800 2050);
DISPLAY 0.872340 (-800 2050);
PAINT GREEN (-800 2050);
DISPLAY INVISIBLE (-800 2050);
FORCEPROP 1 LAST HDL_TAP TRUE
J 2
(-1125 1875);
DISPLAY 0.872340 (-1125 1875);
DISPLAY INVISIBLE (-1125 1875);
FORCEPROP 1 LAST PATH I119
J 2
(-798 2000);
DISPLAY 0.872340 (-798 2000);
PAINT GREEN (-798 2000);
DISPLAY INVISIBLE (-798 2000);
FORCEADD TAP..1
R 2
(-800 1950);
FORCEPROP 3 LASTPIN (-750 1950) SIG_NAME UPI_CPU1_CPU0_P2P2_DP<12>
J 0
(-740 1960);
DISPLAY 0.659574 (-740 1960);
PAINT MONO (-740 1960);
DISPLAY INVISIBLE (-740 1960);
FORCEPROP 1 LASTPIN (-750 1950) BN 12
J 2
(-738 1958);
DISPLAY 0.680851 (-738 1958);
PAINT GREEN (-738 1958);
FORCEPROP 2 LAST CDS_LIB standard
J 0
(-800 1950);
DISPLAY INVISIBLE (-800 1950);
FORCEPROP 1 LAST BODY_TYPE PLUMBING
J 2
(-800 2000);
DISPLAY 0.872340 (-800 2000);
PAINT GREEN (-800 2000);
DISPLAY INVISIBLE (-800 2000);
FORCEPROP 1 LAST HDL_TAP TRUE
J 2
(-1125 1825);
DISPLAY 0.872340 (-1125 1825);
DISPLAY INVISIBLE (-1125 1825);
FORCEPROP 1 LAST PATH I120
J 2
(-798 1950);
DISPLAY 0.872340 (-798 1950);
PAINT GREEN (-798 1950);
DISPLAY INVISIBLE (-798 1950);
FORCEADD TAP..1
R 2
(-800 1800);
FORCEPROP 3 LASTPIN (-750 1800) SIG_NAME UPI_CPU1_CPU0_P2P2_DP<15>
J 0
(-740 1810);
DISPLAY 0.659574 (-740 1810);
PAINT MONO (-740 1810);
DISPLAY INVISIBLE (-740 1810);
FORCEPROP 1 LASTPIN (-750 1800) BN 15
J 2
(-738 1808);
DISPLAY 0.680851 (-738 1808);
PAINT GREEN (-738 1808);
FORCEPROP 2 LAST CDS_LIB standard
J 0
(-800 1800);
DISPLAY INVISIBLE (-800 1800);
FORCEPROP 1 LAST BODY_TYPE PLUMBING
J 2
(-800 1850);
DISPLAY 0.872340 (-800 1850);
PAINT GREEN (-800 1850);
DISPLAY INVISIBLE (-800 1850);
FORCEPROP 1 LAST HDL_TAP TRUE
J 2
(-1125 1675);
DISPLAY 0.872340 (-1125 1675);
DISPLAY INVISIBLE (-1125 1675);
FORCEPROP 1 LAST PATH I121
J 2
(-798 1800);
DISPLAY 0.872340 (-798 1800);
PAINT GREEN (-798 1800);
DISPLAY INVISIBLE (-798 1800);
FORCEADD TAP..1
R 2
(-800 1850);
FORCEPROP 3 LASTPIN (-750 1850) SIG_NAME UPI_CPU1_CPU0_P2P2_DP<14>
J 0
(-740 1860);
DISPLAY 0.659574 (-740 1860);
PAINT MONO (-740 1860);
DISPLAY INVISIBLE (-740 1860);
FORCEPROP 1 LASTPIN (-750 1850) BN 14
J 2
(-738 1858);
DISPLAY 0.680851 (-738 1858);
PAINT GREEN (-738 1858);
FORCEPROP 2 LAST CDS_LIB standard
J 0
(-800 1850);
DISPLAY INVISIBLE (-800 1850);
FORCEPROP 1 LAST BODY_TYPE PLUMBING
J 2
(-800 1900);
DISPLAY 0.872340 (-800 1900);
PAINT GREEN (-800 1900);
DISPLAY INVISIBLE (-800 1900);
FORCEPROP 1 LAST HDL_TAP TRUE
J 2
(-1125 1725);
DISPLAY 0.872340 (-1125 1725);
DISPLAY INVISIBLE (-1125 1725);
FORCEPROP 1 LAST PATH I122
J 2
(-798 1850);
DISPLAY 0.872340 (-798 1850);
PAINT GREEN (-798 1850);
DISPLAY INVISIBLE (-798 1850);
FORCEADD TAP..1
R 2
(-800 2150);
FORCEPROP 3 LASTPIN (-750 2150) SIG_NAME UPI_CPU1_CPU0_P2P2_DP<8>
J 0
(-740 2160);
DISPLAY 0.659574 (-740 2160);
PAINT MONO (-740 2160);
DISPLAY INVISIBLE (-740 2160);
FORCEPROP 1 LASTPIN (-750 2150) BN 8
J 2
(-738 2158);
DISPLAY 0.680851 (-738 2158);
PAINT GREEN (-738 2158);
FORCEPROP 2 LAST CDS_LIB standard
J 0
(-800 2150);
DISPLAY INVISIBLE (-800 2150);
FORCEPROP 1 LAST BODY_TYPE PLUMBING
J 2
(-800 2200);
DISPLAY 0.872340 (-800 2200);
PAINT GREEN (-800 2200);
DISPLAY INVISIBLE (-800 2200);
FORCEPROP 1 LAST HDL_TAP TRUE
J 2
(-1125 2025);
DISPLAY 0.872340 (-1125 2025);
DISPLAY INVISIBLE (-1125 2025);
FORCEPROP 1 LAST PATH I123
J 2
(-798 2150);
DISPLAY 0.872340 (-798 2150);
PAINT GREEN (-798 2150);
DISPLAY INVISIBLE (-798 2150);
FORCEADD TAP..1
R 2
(-800 2200);
FORCEPROP 3 LASTPIN (-750 2200) SIG_NAME UPI_CPU1_CPU0_P2P2_DP<7>
J 0
(-740 2210);
DISPLAY 0.659574 (-740 2210);
PAINT MONO (-740 2210);
DISPLAY INVISIBLE (-740 2210);
FORCEPROP 1 LASTPIN (-750 2200) BN 7
J 2
(-738 2208);
DISPLAY 0.680851 (-738 2208);
PAINT GREEN (-738 2208);
FORCEPROP 2 LAST CDS_LIB standard
J 0
(-800 2200);
PAINT MONO (-800 2200);
DISPLAY INVISIBLE (-800 2200);
FORCEPROP 1 LAST BODY_TYPE PLUMBING
J 2
(-800 2250);
DISPLAY 0.872340 (-800 2250);
PAINT GREEN (-800 2250);
DISPLAY INVISIBLE (-800 2250);
FORCEPROP 1 LAST HDL_TAP TRUE
J 2
(-1125 2075);
DISPLAY 0.872340 (-1125 2075);
DISPLAY INVISIBLE (-1125 2075);
FORCEPROP 1 LAST PATH I124
J 2
(-798 2200);
DISPLAY 0.872340 (-798 2200);
PAINT GREEN (-798 2200);
DISPLAY INVISIBLE (-798 2200);
FORCEADD TAP..1
R 2
(-800 2350);
FORCEPROP 3 LASTPIN (-750 2350) SIG_NAME UPI_CPU1_CPU0_P2P2_DP<4>
J 0
(-740 2360);
DISPLAY 0.659574 (-740 2360);
PAINT MONO (-740 2360);
DISPLAY INVISIBLE (-740 2360);
FORCEPROP 1 LASTPIN (-750 2350) BN 4
J 2
(-738 2358);
DISPLAY 0.680851 (-738 2358);
PAINT GREEN (-738 2358);
FORCEPROP 2 LAST CDS_LIB standard
J 0
(-800 2350);
PAINT MONO (-800 2350);
DISPLAY INVISIBLE (-800 2350);
FORCEPROP 1 LAST BODY_TYPE PLUMBING
J 2
(-800 2400);
DISPLAY 0.872340 (-800 2400);
PAINT GREEN (-800 2400);
DISPLAY INVISIBLE (-800 2400);
FORCEPROP 1 LAST HDL_TAP TRUE
J 2
(-1125 2225);
DISPLAY 0.872340 (-1125 2225);
DISPLAY INVISIBLE (-1125 2225);
FORCEPROP 1 LAST PATH I125
J 2
(-798 2350);
DISPLAY 0.872340 (-798 2350);
PAINT GREEN (-798 2350);
DISPLAY INVISIBLE (-798 2350);
FORCEADD TAP..1
R 2
(-800 2400);
FORCEPROP 3 LASTPIN (-750 2400) SIG_NAME UPI_CPU1_CPU0_P2P2_DP<3>
J 0
(-740 2410);
DISPLAY 0.659574 (-740 2410);
PAINT MONO (-740 2410);
DISPLAY INVISIBLE (-740 2410);
FORCEPROP 1 LASTPIN (-750 2400) BN 3
J 2
(-738 2408);
DISPLAY 0.680851 (-738 2408);
PAINT GREEN (-738 2408);
FORCEPROP 2 LAST CDS_LIB standard
J 0
(-800 2400);
PAINT MONO (-800 2400);
DISPLAY INVISIBLE (-800 2400);
FORCEPROP 1 LAST BODY_TYPE PLUMBING
J 2
(-800 2450);
DISPLAY 0.872340 (-800 2450);
PAINT GREEN (-800 2450);
DISPLAY INVISIBLE (-800 2450);
FORCEPROP 1 LAST HDL_TAP TRUE
J 2
(-1125 2275);
DISPLAY 0.872340 (-1125 2275);
DISPLAY INVISIBLE (-1125 2275);
FORCEPROP 1 LAST PATH I126
J 2
(-798 2400);
DISPLAY 0.872340 (-798 2400);
PAINT GREEN (-798 2400);
DISPLAY INVISIBLE (-798 2400);
FORCEADD TAP..1
R 2
(-800 2450);
FORCEPROP 3 LASTPIN (-750 2450) SIG_NAME UPI_CPU1_CPU0_P2P2_DP<2>
J 0
(-740 2460);
DISPLAY 0.659574 (-740 2460);
PAINT MONO (-740 2460);
DISPLAY INVISIBLE (-740 2460);
FORCEPROP 1 LASTPIN (-750 2450) BN 2
J 2
(-738 2458);
DISPLAY 0.680851 (-738 2458);
PAINT GREEN (-738 2458);
FORCEPROP 2 LAST CDS_LIB standard
J 0
(-800 2450);
PAINT MONO (-800 2450);
DISPLAY INVISIBLE (-800 2450);
FORCEPROP 1 LAST BODY_TYPE PLUMBING
J 2
(-800 2500);
DISPLAY 0.872340 (-800 2500);
PAINT GREEN (-800 2500);
DISPLAY INVISIBLE (-800 2500);
FORCEPROP 1 LAST HDL_TAP TRUE
J 2
(-1125 2325);
DISPLAY 0.872340 (-1125 2325);
DISPLAY INVISIBLE (-1125 2325);
FORCEPROP 1 LAST PATH I127
J 2
(-798 2450);
DISPLAY 0.872340 (-798 2450);
PAINT GREEN (-798 2450);
DISPLAY INVISIBLE (-798 2450);
FORCEADD TAP..1
R 2
(-800 2550);
FORCEPROP 3 LASTPIN (-750 2550) SIG_NAME UPI_CPU1_CPU0_P2P2_DP<0>
J 0
(-740 2560);
DISPLAY 0.659574 (-740 2560);
PAINT MONO (-740 2560);
DISPLAY INVISIBLE (-740 2560);
FORCEPROP 1 LASTPIN (-750 2550) BN 0
J 2
(-738 2558);
DISPLAY 0.680851 (-738 2558);
PAINT GREEN (-738 2558);
FORCEPROP 2 LAST CDS_LIB standard
J 0
(-800 2550);
PAINT MONO (-800 2550);
DISPLAY INVISIBLE (-800 2550);
FORCEPROP 1 LAST BODY_TYPE PLUMBING
J 2
(-800 2600);
DISPLAY 0.872340 (-800 2600);
PAINT GREEN (-800 2600);
DISPLAY INVISIBLE (-800 2600);
FORCEPROP 1 LAST HDL_TAP TRUE
J 2
(-1125 2425);
DISPLAY 0.872340 (-1125 2425);
DISPLAY INVISIBLE (-1125 2425);
FORCEPROP 1 LAST PATH I128
J 2
(-798 2550);
DISPLAY 0.872340 (-798 2550);
PAINT GREEN (-798 2550);
DISPLAY INVISIBLE (-798 2550);
FORCEADD OFFPAGE..1
(-2300 2600);
FORCEPROP 2 LAST $XR0 65 
J 0
(-2551 2600);
DISPLAY 0.638298 (-2551 2600);
PAINT MONO (-2551 2600);
FORCEPROP 2 LAST CDS_LIB standard
J 0
(-2300 2600);
PAINT MONO (-2300 2600);
DISPLAY INVISIBLE (-2300 2600);
FORCEPROP 1 LAST OFFPAGE TRUE
J 0
(-1975 2475);
DISPLAY 0.872340 (-1975 2475);
DISPLAY INVISIBLE (-1975 2475);
FORCEPROP 1 LAST COMMENT_BODY TRUE
J 0
(-2175 2500);
DISPLAY 0.872340 (-2175 2500);
PAINT GREEN (-2175 2500);
DISPLAY INVISIBLE (-2175 2500);
FORCEPROP 2 LAST PATH I129
J 0
(-2550 2650);
DISPLAY 1.021277 (-2550 2650);
DISPLAY INVISIBLE (-2550 2650);
FORCEADD TAP..1
R 2
(-1000 1500);
FORCEPROP 3 LASTPIN (-950 1500) SIG_NAME UPI_CPU1_CPU0_P2P2_DN<21>
J 0
(-940 1510);
DISPLAY 0.659574 (-940 1510);
PAINT MONO (-940 1510);
DISPLAY INVISIBLE (-940 1510);
FORCEPROP 1 LASTPIN (-950 1500) BN 21
J 2
(-938 1508);
DISPLAY 0.680851 (-938 1508);
PAINT GREEN (-938 1508);
FORCEPROP 2 LAST CDS_LIB standard
J 0
(-1000 1500);
DISPLAY INVISIBLE (-1000 1500);
FORCEPROP 1 LAST BODY_TYPE PLUMBING
J 2
(-1000 1550);
DISPLAY 0.872340 (-1000 1550);
PAINT GREEN (-1000 1550);
DISPLAY INVISIBLE (-1000 1550);
FORCEPROP 1 LAST HDL_TAP TRUE
J 2
(-1325 1375);
DISPLAY 0.872340 (-1325 1375);
DISPLAY INVISIBLE (-1325 1375);
FORCEPROP 1 LAST PATH I130
J 2
(-998 1500);
DISPLAY 0.872340 (-998 1500);
PAINT GREEN (-998 1500);
DISPLAY INVISIBLE (-998 1500);
FORCEADD TAP..1
R 2
(-800 2750);
FORCEPROP 3 LASTPIN (-750 2750) SIG_NAME UPI_CPU1_CPU0_P2P2_DP<21>
J 0
(-740 2760);
DISPLAY 0.659574 (-740 2760);
PAINT MONO (-740 2760);
DISPLAY INVISIBLE (-740 2760);
FORCEPROP 1 LASTPIN (-750 2750) BN 21
J 2
(-738 2758);
DISPLAY 0.680851 (-738 2758);
PAINT GREEN (-738 2758);
FORCEPROP 2 LAST CDS_LIB standard
J 0
(-800 2750);
DISPLAY INVISIBLE (-800 2750);
FORCEPROP 1 LAST BODY_TYPE PLUMBING
J 2
(-800 2800);
DISPLAY 0.872340 (-800 2800);
PAINT GREEN (-800 2800);
DISPLAY INVISIBLE (-800 2800);
FORCEPROP 1 LAST HDL_TAP TRUE
J 2
(-1125 2625);
DISPLAY 0.872340 (-1125 2625);
DISPLAY INVISIBLE (-1125 2625);
FORCEPROP 1 LAST PATH I131
J 2
(-798 2750);
DISPLAY 0.872340 (-798 2750);
PAINT GREEN (-798 2750);
DISPLAY INVISIBLE (-798 2750);
FORCEADD TAP..1
R 2
(-1000 1900);
FORCEPROP 3 LASTPIN (-950 1900) SIG_NAME UPI_CPU1_CPU0_P2P2_DN<13>
J 0
(-940 1910);
DISPLAY 0.659574 (-940 1910);
PAINT MONO (-940 1910);
DISPLAY INVISIBLE (-940 1910);
FORCEPROP 1 LASTPIN (-950 1900) BN 13
J 2
(-938 1908);
DISPLAY 0.680851 (-938 1908);
PAINT GREEN (-938 1908);
FORCEPROP 2 LAST CDS_LIB standard
J 0
(-1000 1900);
DISPLAY INVISIBLE (-1000 1900);
FORCEPROP 1 LAST BODY_TYPE PLUMBING
J 2
(-1000 1950);
DISPLAY 0.872340 (-1000 1950);
PAINT GREEN (-1000 1950);
DISPLAY INVISIBLE (-1000 1950);
FORCEPROP 1 LAST HDL_TAP TRUE
J 2
(-1325 1775);
DISPLAY 0.872340 (-1325 1775);
DISPLAY INVISIBLE (-1325 1775);
FORCEPROP 1 LAST PATH I14
J 2
(-998 1900);
DISPLAY 0.872340 (-998 1900);
PAINT GREEN (-998 1900);
DISPLAY INVISIBLE (-998 1900);
FORCEADD TAP..1
R 2
(-1000 2050);
FORCEPROP 3 LASTPIN (-950 2050) SIG_NAME UPI_CPU1_CPU0_P2P2_DN<10>
J 0
(-940 2060);
DISPLAY 0.659574 (-940 2060);
PAINT MONO (-940 2060);
DISPLAY INVISIBLE (-940 2060);
FORCEPROP 1 LASTPIN (-950 2050) BN 10
J 2
(-938 2058);
DISPLAY 0.680851 (-938 2058);
PAINT GREEN (-938 2058);
FORCEPROP 2 LAST CDS_LIB standard
J 0
(-1000 2050);
DISPLAY INVISIBLE (-1000 2050);
FORCEPROP 1 LAST BODY_TYPE PLUMBING
J 2
(-1000 2100);
DISPLAY 0.872340 (-1000 2100);
PAINT GREEN (-1000 2100);
DISPLAY INVISIBLE (-1000 2100);
FORCEPROP 1 LAST HDL_TAP TRUE
J 2
(-1325 1925);
DISPLAY 0.872340 (-1325 1925);
DISPLAY INVISIBLE (-1325 1925);
FORCEPROP 1 LAST PATH I16
J 2
(-998 2050);
DISPLAY 0.872340 (-998 2050);
PAINT GREEN (-998 2050);
DISPLAY INVISIBLE (-998 2050);
FORCEADD TAP..1
R 2
(-1000 2100);
FORCEPROP 3 LASTPIN (-950 2100) SIG_NAME UPI_CPU1_CPU0_P2P2_DN<9>
J 0
(-940 2110);
DISPLAY 0.659574 (-940 2110);
PAINT MONO (-940 2110);
DISPLAY INVISIBLE (-940 2110);
FORCEPROP 1 LASTPIN (-950 2100) BN 9
J 2
(-938 2108);
DISPLAY 0.680851 (-938 2108);
PAINT GREEN (-938 2108);
FORCEPROP 2 LAST CDS_LIB standard
J 0
(-1000 2100);
DISPLAY INVISIBLE (-1000 2100);
FORCEPROP 1 LAST BODY_TYPE PLUMBING
J 2
(-1000 2150);
DISPLAY 0.872340 (-1000 2150);
PAINT GREEN (-1000 2150);
DISPLAY INVISIBLE (-1000 2150);
FORCEPROP 1 LAST HDL_TAP TRUE
J 2
(-1325 1975);
DISPLAY 0.872340 (-1325 1975);
DISPLAY INVISIBLE (-1325 1975);
FORCEPROP 1 LAST PATH I17
J 2
(-998 2100);
DISPLAY 0.872340 (-998 2100);
PAINT GREEN (-998 2100);
DISPLAY INVISIBLE (-998 2100);
FORCEADD OFFPAGE..1
(-2300 3925);
FORCEPROP 2 LAST $XR0 65 
J 0
(-2551 3925);
DISPLAY 0.638298 (-2551 3925);
PAINT MONO (-2551 3925);
FORCEPROP 2 LAST CDS_LIB standard
J 0
(-2300 3925);
PAINT MONO (-2300 3925);
DISPLAY INVISIBLE (-2300 3925);
FORCEPROP 1 LAST OFFPAGE TRUE
J 0
(-1975 3800);
DISPLAY 0.872340 (-1975 3800);
DISPLAY INVISIBLE (-1975 3800);
FORCEPROP 1 LAST COMMENT_BODY TRUE
J 0
(-2175 3825);
DISPLAY 0.872340 (-2175 3825);
PAINT GREEN (-2175 3825);
DISPLAY INVISIBLE (-2175 3825);
FORCEPROP 2 LAST PATH I2
J 0
(-2250 4000);
DISPLAY 1.021277 (-2250 4000);
DISPLAY INVISIBLE (-2250 4000);
FORCEADD TAP..1
R 2
(-1000 2250);
FORCEPROP 3 LASTPIN (-950 2250) SIG_NAME UPI_CPU1_CPU0_P2P2_DN<6>
J 0
(-940 2260);
DISPLAY 0.659574 (-940 2260);
PAINT MONO (-940 2260);
DISPLAY INVISIBLE (-940 2260);
FORCEPROP 1 LASTPIN (-950 2250) BN 6
J 2
(-938 2258);
DISPLAY 0.680851 (-938 2258);
PAINT GREEN (-938 2258);
FORCEPROP 2 LAST CDS_LIB standard
J 0
(-1000 2250);
PAINT MONO (-1000 2250);
DISPLAY INVISIBLE (-1000 2250);
FORCEPROP 1 LAST BODY_TYPE PLUMBING
J 2
(-1000 2300);
DISPLAY 0.872340 (-1000 2300);
PAINT GREEN (-1000 2300);
DISPLAY INVISIBLE (-1000 2300);
FORCEPROP 1 LAST HDL_TAP TRUE
J 2
(-1325 2125);
DISPLAY 0.872340 (-1325 2125);
DISPLAY INVISIBLE (-1325 2125);
FORCEPROP 1 LAST PATH I20
J 2
(-998 2250);
DISPLAY 0.872340 (-998 2250);
PAINT GREEN (-998 2250);
DISPLAY INVISIBLE (-998 2250);
FORCEADD TAP..1
R 2
(-1000 2300);
FORCEPROP 3 LASTPIN (-950 2300) SIG_NAME UPI_CPU1_CPU0_P2P2_DN<5>
J 0
(-940 2310);
DISPLAY 0.659574 (-940 2310);
PAINT MONO (-940 2310);
DISPLAY INVISIBLE (-940 2310);
FORCEPROP 1 LASTPIN (-950 2300) BN 5
J 2
(-938 2308);
DISPLAY 0.680851 (-938 2308);
PAINT GREEN (-938 2308);
FORCEPROP 2 LAST CDS_LIB standard
J 0
(-1000 2300);
PAINT MONO (-1000 2300);
DISPLAY INVISIBLE (-1000 2300);
FORCEPROP 1 LAST BODY_TYPE PLUMBING
J 2
(-1000 2350);
DISPLAY 0.872340 (-1000 2350);
PAINT GREEN (-1000 2350);
DISPLAY INVISIBLE (-1000 2350);
FORCEPROP 1 LAST HDL_TAP TRUE
J 2
(-1325 2175);
DISPLAY 0.872340 (-1325 2175);
DISPLAY INVISIBLE (-1325 2175);
FORCEPROP 1 LAST PATH I22
J 2
(-998 2300);
DISPLAY 0.872340 (-998 2300);
PAINT GREEN (-998 2300);
DISPLAY INVISIBLE (-998 2300);
FORCEADD TAP..1
R 2
(-1000 2500);
FORCEPROP 3 LASTPIN (-950 2500) SIG_NAME UPI_CPU1_CPU0_P2P2_DN<1>
J 0
(-940 2510);
DISPLAY 0.659574 (-940 2510);
PAINT MONO (-940 2510);
DISPLAY INVISIBLE (-940 2510);
FORCEPROP 1 LASTPIN (-950 2500) BN 1
J 2
(-938 2508);
DISPLAY 0.680851 (-938 2508);
PAINT GREEN (-938 2508);
FORCEPROP 2 LAST CDS_LIB standard
J 0
(-1000 2500);
PAINT MONO (-1000 2500);
DISPLAY INVISIBLE (-1000 2500);
FORCEPROP 1 LAST BODY_TYPE PLUMBING
J 2
(-1000 2550);
DISPLAY 0.872340 (-1000 2550);
PAINT GREEN (-1000 2550);
DISPLAY INVISIBLE (-1000 2550);
FORCEPROP 1 LAST HDL_TAP TRUE
J 2
(-1325 2375);
DISPLAY 0.872340 (-1325 2375);
DISPLAY INVISIBLE (-1325 2375);
FORCEPROP 1 LAST PATH I26
J 2
(-998 2500);
DISPLAY 0.872340 (-998 2500);
PAINT GREEN (-998 2500);
DISPLAY INVISIBLE (-998 2500);
FORCEADD TAP..1
R 2
(-800 2650);
FORCEPROP 3 LASTPIN (-750 2650) SIG_NAME UPI_CPU1_CPU0_P2P2_DP<23>
J 0
(-740 2660);
DISPLAY 0.659574 (-740 2660);
PAINT MONO (-740 2660);
DISPLAY INVISIBLE (-740 2660);
FORCEPROP 1 LASTPIN (-750 2650) BN 23
J 2
(-738 2658);
DISPLAY 0.680851 (-738 2658);
PAINT GREEN (-738 2658);
FORCEPROP 2 LAST CDS_LIB standard
J 0
(-800 2650);
DISPLAY INVISIBLE (-800 2650);
FORCEPROP 1 LAST BODY_TYPE PLUMBING
J 2
(-800 2700);
DISPLAY 0.872340 (-800 2700);
PAINT GREEN (-800 2700);
DISPLAY INVISIBLE (-800 2700);
FORCEPROP 1 LAST HDL_TAP TRUE
J 2
(-1125 2525);
DISPLAY 0.872340 (-1125 2525);
DISPLAY INVISIBLE (-1125 2525);
FORCEPROP 1 LAST PATH I28
J 2
(-798 2650);
DISPLAY 0.872340 (-798 2650);
PAINT GREEN (-798 2650);
DISPLAY INVISIBLE (-798 2650);
FORCEADD TAP..1
R 2
(-800 2800);
FORCEPROP 3 LASTPIN (-750 2800) SIG_NAME UPI_CPU1_CPU0_P2P2_DP<20>
J 0
(-740 2810);
DISPLAY 0.659574 (-740 2810);
PAINT MONO (-740 2810);
DISPLAY INVISIBLE (-740 2810);
FORCEPROP 1 LASTPIN (-750 2800) BN 20
J 2
(-738 2808);
DISPLAY 0.680851 (-738 2808);
PAINT GREEN (-738 2808);
FORCEPROP 2 LAST CDS_LIB standard
J 0
(-800 2800);
DISPLAY INVISIBLE (-800 2800);
FORCEPROP 1 LAST BODY_TYPE PLUMBING
J 2
(-800 2850);
DISPLAY 0.872340 (-800 2850);
PAINT GREEN (-800 2850);
DISPLAY INVISIBLE (-800 2850);
FORCEPROP 1 LAST HDL_TAP TRUE
J 2
(-1125 2675);
DISPLAY 0.872340 (-1125 2675);
DISPLAY INVISIBLE (-1125 2675);
FORCEPROP 1 LAST PATH I31
J 2
(-798 2800);
DISPLAY 0.872340 (-798 2800);
PAINT GREEN (-798 2800);
DISPLAY INVISIBLE (-798 2800);
FORCEADD TAP..1
R 2
(-800 2850);
FORCEPROP 3 LASTPIN (-750 2850) SIG_NAME UPI_CPU1_CPU0_P2P2_DP<19>
J 0
(-740 2860);
DISPLAY 0.659574 (-740 2860);
PAINT MONO (-740 2860);
DISPLAY INVISIBLE (-740 2860);
FORCEPROP 1 LASTPIN (-750 2850) BN 19
J 2
(-738 2858);
DISPLAY 0.680851 (-738 2858);
PAINT GREEN (-738 2858);
FORCEPROP 2 LAST CDS_LIB standard
J 0
(-800 2850);
DISPLAY INVISIBLE (-800 2850);
FORCEPROP 1 LAST BODY_TYPE PLUMBING
J 2
(-800 2900);
DISPLAY 0.872340 (-800 2900);
PAINT GREEN (-800 2900);
DISPLAY INVISIBLE (-800 2900);
FORCEPROP 1 LAST HDL_TAP TRUE
J 2
(-1125 2725);
DISPLAY 0.872340 (-1125 2725);
DISPLAY INVISIBLE (-1125 2725);
FORCEPROP 1 LAST PATH I32
J 2
(-798 2850);
DISPLAY 0.872340 (-798 2850);
PAINT GREEN (-798 2850);
DISPLAY INVISIBLE (-798 2850);
FORCEADD TAP..1
R 2
(-800 2900);
FORCEPROP 3 LASTPIN (-750 2900) SIG_NAME UPI_CPU1_CPU0_P2P2_DP<18>
J 0
(-740 2910);
DISPLAY 0.659574 (-740 2910);
PAINT MONO (-740 2910);
DISPLAY INVISIBLE (-740 2910);
FORCEPROP 1 LASTPIN (-750 2900) BN 18
J 2
(-738 2908);
DISPLAY 0.680851 (-738 2908);
PAINT GREEN (-738 2908);
FORCEPROP 2 LAST CDS_LIB standard
J 0
(-800 2900);
DISPLAY INVISIBLE (-800 2900);
FORCEPROP 1 LAST BODY_TYPE PLUMBING
J 2
(-800 2950);
DISPLAY 0.872340 (-800 2950);
PAINT GREEN (-800 2950);
DISPLAY INVISIBLE (-800 2950);
FORCEPROP 1 LAST HDL_TAP TRUE
J 2
(-1125 2775);
DISPLAY 0.872340 (-1125 2775);
DISPLAY INVISIBLE (-1125 2775);
FORCEPROP 1 LAST PATH I33
J 2
(-798 2900);
DISPLAY 0.872340 (-798 2900);
PAINT GREEN (-798 2900);
DISPLAY INVISIBLE (-798 2900);
FORCEADD TAP..1
R 2
(-800 2950);
FORCEPROP 3 LASTPIN (-750 2950) SIG_NAME UPI_CPU1_CPU0_P2P2_DP<17>
J 0
(-740 2960);
DISPLAY 0.659574 (-740 2960);
PAINT MONO (-740 2960);
DISPLAY INVISIBLE (-740 2960);
FORCEPROP 1 LASTPIN (-750 2950) BN 17
J 2
(-738 2958);
DISPLAY 0.680851 (-738 2958);
PAINT GREEN (-738 2958);
FORCEPROP 2 LAST CDS_LIB standard
J 0
(-800 2950);
DISPLAY INVISIBLE (-800 2950);
FORCEPROP 1 LAST BODY_TYPE PLUMBING
J 2
(-800 3000);
DISPLAY 0.872340 (-800 3000);
PAINT GREEN (-800 3000);
DISPLAY INVISIBLE (-800 3000);
FORCEPROP 1 LAST HDL_TAP TRUE
J 2
(-1125 2825);
DISPLAY 0.872340 (-1125 2825);
DISPLAY INVISIBLE (-1125 2825);
FORCEPROP 1 LAST PATH I34
J 2
(-798 2950);
DISPLAY 0.872340 (-798 2950);
PAINT GREEN (-798 2950);
DISPLAY INVISIBLE (-798 2950);
FORCEADD TAP..1
R 2
(-800 3150);
FORCEPROP 3 LASTPIN (-750 3150) SIG_NAME UPI_CPU1_CPU0_P2P2_DP<13>
J 0
(-740 3160);
DISPLAY 0.659574 (-740 3160);
PAINT MONO (-740 3160);
DISPLAY INVISIBLE (-740 3160);
FORCEPROP 1 LASTPIN (-750 3150) BN 13
J 2
(-738 3158);
DISPLAY 0.680851 (-738 3158);
PAINT GREEN (-738 3158);
FORCEPROP 2 LAST CDS_LIB standard
J 0
(-800 3150);
DISPLAY INVISIBLE (-800 3150);
FORCEPROP 1 LAST BODY_TYPE PLUMBING
J 2
(-800 3200);
DISPLAY 0.872340 (-800 3200);
PAINT GREEN (-800 3200);
DISPLAY INVISIBLE (-800 3200);
FORCEPROP 1 LAST HDL_TAP TRUE
J 2
(-1125 3025);
DISPLAY 0.872340 (-1125 3025);
DISPLAY INVISIBLE (-1125 3025);
FORCEPROP 1 LAST PATH I38
J 2
(-798 3150);
DISPLAY 0.872340 (-798 3150);
PAINT GREEN (-798 3150);
DISPLAY INVISIBLE (-798 3150);
FORCEADD TAP..1
R 2
(-800 3350);
FORCEPROP 3 LASTPIN (-750 3350) SIG_NAME UPI_CPU1_CPU0_P2P2_DP<9>
J 0
(-740 3360);
DISPLAY 0.659574 (-740 3360);
PAINT MONO (-740 3360);
DISPLAY INVISIBLE (-740 3360);
FORCEPROP 1 LASTPIN (-750 3350) BN 9
J 2
(-738 3358);
DISPLAY 0.680851 (-738 3358);
PAINT GREEN (-738 3358);
FORCEPROP 2 LAST CDS_LIB standard
J 0
(-800 3350);
DISPLAY INVISIBLE (-800 3350);
FORCEPROP 1 LAST BODY_TYPE PLUMBING
J 2
(-800 3400);
DISPLAY 0.872340 (-800 3400);
PAINT GREEN (-800 3400);
DISPLAY INVISIBLE (-800 3400);
FORCEPROP 1 LAST HDL_TAP TRUE
J 2
(-1125 3225);
DISPLAY 0.872340 (-1125 3225);
DISPLAY INVISIBLE (-1125 3225);
FORCEPROP 1 LAST PATH I41
J 2
(-798 3350);
DISPLAY 0.872340 (-798 3350);
PAINT GREEN (-798 3350);
DISPLAY INVISIBLE (-798 3350);
FORCEADD TAP..1
R 2
(-800 3300);
FORCEPROP 3 LASTPIN (-750 3300) SIG_NAME UPI_CPU1_CPU0_P2P2_DP<10>
J 0
(-740 3310);
DISPLAY 0.659574 (-740 3310);
PAINT MONO (-740 3310);
DISPLAY INVISIBLE (-740 3310);
FORCEPROP 1 LASTPIN (-750 3300) BN 10
J 2
(-738 3308);
DISPLAY 0.680851 (-738 3308);
PAINT GREEN (-738 3308);
FORCEPROP 2 LAST CDS_LIB standard
J 0
(-800 3300);
DISPLAY INVISIBLE (-800 3300);
FORCEPROP 1 LAST BODY_TYPE PLUMBING
J 2
(-800 3350);
DISPLAY 0.872340 (-800 3350);
PAINT GREEN (-800 3350);
DISPLAY INVISIBLE (-800 3350);
FORCEPROP 1 LAST HDL_TAP TRUE
J 2
(-1125 3175);
DISPLAY 0.872340 (-1125 3175);
DISPLAY INVISIBLE (-1125 3175);
FORCEPROP 1 LAST PATH I42
J 2
(-798 3300);
DISPLAY 0.872340 (-798 3300);
PAINT GREEN (-798 3300);
DISPLAY INVISIBLE (-798 3300);
FORCEADD TAP..1
R 2
(-800 3550);
FORCEPROP 3 LASTPIN (-750 3550) SIG_NAME UPI_CPU1_CPU0_P2P2_DP<5>
J 0
(-740 3560);
DISPLAY 0.659574 (-740 3560);
PAINT MONO (-740 3560);
DISPLAY INVISIBLE (-740 3560);
FORCEPROP 1 LASTPIN (-750 3550) BN 5
J 2
(-738 3558);
DISPLAY 0.680851 (-738 3558);
PAINT GREEN (-738 3558);
FORCEPROP 2 LAST CDS_LIB standard
J 0
(-800 3550);
DISPLAY INVISIBLE (-800 3550);
FORCEPROP 1 LAST BODY_TYPE PLUMBING
J 2
(-800 3600);
DISPLAY 0.872340 (-800 3600);
PAINT GREEN (-800 3600);
DISPLAY INVISIBLE (-800 3600);
FORCEPROP 1 LAST HDL_TAP TRUE
J 2
(-1125 3425);
DISPLAY 0.872340 (-1125 3425);
DISPLAY INVISIBLE (-1125 3425);
FORCEPROP 1 LAST PATH I45
J 2
(-798 3550);
DISPLAY 0.872340 (-798 3550);
PAINT GREEN (-798 3550);
DISPLAY INVISIBLE (-798 3550);
FORCEADD TAP..1
R 2
(-800 3500);
FORCEPROP 3 LASTPIN (-750 3500) SIG_NAME UPI_CPU1_CPU0_P2P2_DP<6>
J 0
(-740 3510);
DISPLAY 0.659574 (-740 3510);
PAINT MONO (-740 3510);
DISPLAY INVISIBLE (-740 3510);
FORCEPROP 1 LASTPIN (-750 3500) BN 6
J 2
(-738 3508);
DISPLAY 0.680851 (-738 3508);
PAINT GREEN (-738 3508);
FORCEPROP 2 LAST CDS_LIB standard
J 0
(-800 3500);
DISPLAY INVISIBLE (-800 3500);
FORCEPROP 1 LAST BODY_TYPE PLUMBING
J 2
(-800 3550);
DISPLAY 0.872340 (-800 3550);
PAINT GREEN (-800 3550);
DISPLAY INVISIBLE (-800 3550);
FORCEPROP 1 LAST HDL_TAP TRUE
J 2
(-1125 3375);
DISPLAY 0.872340 (-1125 3375);
DISPLAY INVISIBLE (-1125 3375);
FORCEPROP 1 LAST PATH I46
J 2
(-798 3500);
DISPLAY 0.872340 (-798 3500);
PAINT GREEN (-798 3500);
DISPLAY INVISIBLE (-798 3500);
FORCEADD TAP..1
R 2
(-1000 1400);
FORCEPROP 3 LASTPIN (-950 1400) SIG_NAME UPI_CPU1_CPU0_P2P2_DN<23>
J 0
(-940 1410);
DISPLAY 0.659574 (-940 1410);
PAINT MONO (-940 1410);
DISPLAY INVISIBLE (-940 1410);
FORCEPROP 1 LASTPIN (-950 1400) BN 23
J 2
(-938 1408);
DISPLAY 0.680851 (-938 1408);
PAINT GREEN (-938 1408);
FORCEPROP 2 LAST CDS_LIB standard
J 0
(-1000 1400);
DISPLAY INVISIBLE (-1000 1400);
FORCEPROP 1 LAST BODY_TYPE PLUMBING
J 2
(-1000 1450);
DISPLAY 0.872340 (-1000 1450);
PAINT GREEN (-1000 1450);
DISPLAY INVISIBLE (-1000 1450);
FORCEPROP 1 LAST HDL_TAP TRUE
J 2
(-1325 1275);
DISPLAY 0.872340 (-1325 1275);
DISPLAY INVISIBLE (-1325 1275);
FORCEPROP 1 LAST PATH I5
J 2
(-998 1400);
DISPLAY 0.872340 (-998 1400);
PAINT GREEN (-998 1400);
DISPLAY INVISIBLE (-998 1400);
FORCEADD TAP..1
R 2
(-800 3750);
FORCEPROP 3 LASTPIN (-750 3750) SIG_NAME UPI_CPU1_CPU0_P2P2_DP<1>
J 0
(-740 3760);
DISPLAY 0.659574 (-740 3760);
PAINT MONO (-740 3760);
DISPLAY INVISIBLE (-740 3760);
FORCEPROP 1 LASTPIN (-750 3750) BN 1
J 2
(-738 3758);
DISPLAY 0.680851 (-738 3758);
PAINT GREEN (-738 3758);
FORCEPROP 2 LAST CDS_LIB standard
J 0
(-800 3750);
DISPLAY INVISIBLE (-800 3750);
FORCEPROP 1 LAST BODY_TYPE PLUMBING
J 2
(-800 3800);
DISPLAY 0.872340 (-800 3800);
PAINT GREEN (-800 3800);
DISPLAY INVISIBLE (-800 3800);
FORCEPROP 1 LAST HDL_TAP TRUE
J 2
(-1125 3625);
DISPLAY 0.872340 (-1125 3625);
DISPLAY INVISIBLE (-1125 3625);
FORCEPROP 1 LAST PATH I50
J 2
(-798 3750);
DISPLAY 0.872340 (-798 3750);
PAINT GREEN (-798 3750);
DISPLAY INVISIBLE (-798 3750);
FORCEADD TAP..1
(2575 1500);
FORCEPROP 3 LASTPIN (2525 1500) SIG_NAME UPI_CPU0_CPU1_P2P2_DN<21>
J 0
(2535 1510);
DISPLAY 0.659574 (2535 1510);
PAINT MONO (2535 1510);
DISPLAY INVISIBLE (2535 1510);
FORCEPROP 1 LASTPIN (2525 1500) BN 21
J 0
(2513 1508);
DISPLAY 0.680851 (2513 1508);
PAINT GREEN (2513 1508);
FORCEPROP 2 LAST CDS_LIB standard
J 0
(2575 1500);
PAINT MONO (2575 1500);
DISPLAY INVISIBLE (2575 1500);
FORCEPROP 1 LAST BODY_TYPE PLUMBING
J 0
(2575 1550);
DISPLAY 0.872340 (2575 1550);
PAINT GREEN (2575 1550);
DISPLAY INVISIBLE (2575 1550);
FORCEPROP 1 LAST HDL_TAP TRUE
J 0
(2900 1375);
DISPLAY 0.872340 (2900 1375);
DISPLAY INVISIBLE (2900 1375);
FORCEPROP 1 LAST PATH I52
J 0
(2573 1500);
DISPLAY 0.872340 (2573 1500);
PAINT GREEN (2573 1500);
DISPLAY INVISIBLE (2573 1500);
FORCEADD TAP..1
(2575 1450);
FORCEPROP 3 LASTPIN (2525 1450) SIG_NAME UPI_CPU0_CPU1_P2P2_DN<22>
J 0
(2535 1460);
DISPLAY 0.659574 (2535 1460);
PAINT MONO (2535 1460);
DISPLAY INVISIBLE (2535 1460);
FORCEPROP 1 LASTPIN (2525 1450) BN 22
J 0
(2513 1458);
DISPLAY 0.680851 (2513 1458);
PAINT GREEN (2513 1458);
FORCEPROP 2 LAST CDS_LIB standard
J 0
(2575 1450);
PAINT MONO (2575 1450);
DISPLAY INVISIBLE (2575 1450);
FORCEPROP 1 LAST BODY_TYPE PLUMBING
J 0
(2575 1500);
DISPLAY 0.872340 (2575 1500);
PAINT GREEN (2575 1500);
DISPLAY INVISIBLE (2575 1500);
FORCEPROP 1 LAST HDL_TAP TRUE
J 0
(2900 1325);
DISPLAY 0.872340 (2900 1325);
DISPLAY INVISIBLE (2900 1325);
FORCEPROP 1 LAST PATH I53
J 0
(2573 1450);
DISPLAY 0.872340 (2573 1450);
PAINT GREEN (2573 1450);
DISPLAY INVISIBLE (2573 1450);
FORCEADD TAP..1
(2575 1400);
FORCEPROP 3 LASTPIN (2525 1400) SIG_NAME UPI_CPU0_CPU1_P2P2_DN<23>
J 0
(2535 1410);
DISPLAY 0.659574 (2535 1410);
PAINT MONO (2535 1410);
DISPLAY INVISIBLE (2535 1410);
FORCEPROP 1 LASTPIN (2525 1400) BN 23
J 0
(2513 1408);
DISPLAY 0.680851 (2513 1408);
PAINT GREEN (2513 1408);
FORCEPROP 2 LAST CDS_LIB standard
J 0
(2575 1400);
PAINT MONO (2575 1400);
DISPLAY INVISIBLE (2575 1400);
FORCEPROP 1 LAST BODY_TYPE PLUMBING
J 0
(2575 1450);
DISPLAY 0.872340 (2575 1450);
PAINT GREEN (2575 1450);
DISPLAY INVISIBLE (2575 1450);
FORCEPROP 1 LAST HDL_TAP TRUE
J 0
(2900 1275);
DISPLAY 0.872340 (2900 1275);
DISPLAY INVISIBLE (2900 1275);
FORCEPROP 1 LAST PATH I54
J 0
(2573 1400);
DISPLAY 0.872340 (2573 1400);
PAINT GREEN (2573 1400);
DISPLAY INVISIBLE (2573 1400);
FORCEADD TAP..1
(2575 1600);
FORCEPROP 3 LASTPIN (2525 1600) SIG_NAME UPI_CPU0_CPU1_P2P2_DN<19>
J 0
(2535 1610);
DISPLAY 0.659574 (2535 1610);
PAINT MONO (2535 1610);
DISPLAY INVISIBLE (2535 1610);
FORCEPROP 1 LASTPIN (2525 1600) BN 19
J 0
(2513 1608);
DISPLAY 0.680851 (2513 1608);
PAINT GREEN (2513 1608);
FORCEPROP 2 LAST CDS_LIB standard
J 0
(2575 1600);
PAINT MONO (2575 1600);
DISPLAY INVISIBLE (2575 1600);
FORCEPROP 1 LAST BODY_TYPE PLUMBING
J 0
(2575 1650);
DISPLAY 0.872340 (2575 1650);
PAINT GREEN (2575 1650);
DISPLAY INVISIBLE (2575 1650);
FORCEPROP 1 LAST HDL_TAP TRUE
J 0
(2900 1475);
DISPLAY 0.872340 (2900 1475);
DISPLAY INVISIBLE (2900 1475);
FORCEPROP 1 LAST PATH I55
J 0
(2573 1600);
DISPLAY 0.872340 (2573 1600);
PAINT GREEN (2573 1600);
DISPLAY INVISIBLE (2573 1600);
FORCEADD TAP..1
(2575 1650);
FORCEPROP 3 LASTPIN (2525 1650) SIG_NAME UPI_CPU0_CPU1_P2P2_DN<18>
J 0
(2535 1660);
DISPLAY 0.659574 (2535 1660);
PAINT MONO (2535 1660);
DISPLAY INVISIBLE (2535 1660);
FORCEPROP 1 LASTPIN (2525 1650) BN 18
J 0
(2513 1658);
DISPLAY 0.680851 (2513 1658);
PAINT GREEN (2513 1658);
FORCEPROP 2 LAST CDS_LIB standard
J 0
(2575 1650);
PAINT MONO (2575 1650);
DISPLAY INVISIBLE (2575 1650);
FORCEPROP 1 LAST BODY_TYPE PLUMBING
J 0
(2575 1700);
DISPLAY 0.872340 (2575 1700);
PAINT GREEN (2575 1700);
DISPLAY INVISIBLE (2575 1700);
FORCEPROP 1 LAST HDL_TAP TRUE
J 0
(2900 1525);
DISPLAY 0.872340 (2900 1525);
DISPLAY INVISIBLE (2900 1525);
FORCEPROP 1 LAST PATH I56
J 0
(2573 1650);
DISPLAY 0.872340 (2573 1650);
PAINT GREEN (2573 1650);
DISPLAY INVISIBLE (2573 1650);
FORCEADD TAP..1
(2575 1550);
FORCEPROP 3 LASTPIN (2525 1550) SIG_NAME UPI_CPU0_CPU1_P2P2_DN<20>
J 0
(2535 1560);
DISPLAY 0.659574 (2535 1560);
PAINT MONO (2535 1560);
DISPLAY INVISIBLE (2535 1560);
FORCEPROP 1 LASTPIN (2525 1550) BN 20
J 0
(2513 1558);
DISPLAY 0.680851 (2513 1558);
PAINT GREEN (2513 1558);
FORCEPROP 2 LAST CDS_LIB standard
J 0
(2575 1550);
PAINT MONO (2575 1550);
DISPLAY INVISIBLE (2575 1550);
FORCEPROP 1 LAST BODY_TYPE PLUMBING
J 0
(2575 1600);
DISPLAY 0.872340 (2575 1600);
PAINT GREEN (2575 1600);
DISPLAY INVISIBLE (2575 1600);
FORCEPROP 1 LAST HDL_TAP TRUE
J 0
(2900 1425);
DISPLAY 0.872340 (2900 1425);
DISPLAY INVISIBLE (2900 1425);
FORCEPROP 1 LAST PATH I57
J 0
(2573 1550);
DISPLAY 0.872340 (2573 1550);
PAINT GREEN (2573 1550);
DISPLAY INVISIBLE (2573 1550);
FORCEADD TAP..1
(2575 1700);
FORCEPROP 3 LASTPIN (2525 1700) SIG_NAME UPI_CPU0_CPU1_P2P2_DN<17>
J 0
(2535 1710);
DISPLAY 0.659574 (2535 1710);
PAINT MONO (2535 1710);
DISPLAY INVISIBLE (2535 1710);
FORCEPROP 1 LASTPIN (2525 1700) BN 17
J 0
(2513 1708);
DISPLAY 0.680851 (2513 1708);
PAINT GREEN (2513 1708);
FORCEPROP 2 LAST CDS_LIB standard
J 0
(2575 1700);
PAINT MONO (2575 1700);
DISPLAY INVISIBLE (2575 1700);
FORCEPROP 1 LAST BODY_TYPE PLUMBING
J 0
(2575 1750);
DISPLAY 0.872340 (2575 1750);
PAINT GREEN (2575 1750);
DISPLAY INVISIBLE (2575 1750);
FORCEPROP 1 LAST HDL_TAP TRUE
J 0
(2900 1575);
DISPLAY 0.872340 (2900 1575);
DISPLAY INVISIBLE (2900 1575);
FORCEPROP 1 LAST PATH I58
J 0
(2573 1700);
DISPLAY 0.872340 (2573 1700);
PAINT GREEN (2573 1700);
DISPLAY INVISIBLE (2573 1700);
FORCEADD TAP..1
(2575 1750);
FORCEPROP 3 LASTPIN (2525 1750) SIG_NAME UPI_CPU0_CPU1_P2P2_DN<16>
J 0
(2535 1760);
DISPLAY 0.659574 (2535 1760);
PAINT MONO (2535 1760);
DISPLAY INVISIBLE (2535 1760);
FORCEPROP 1 LASTPIN (2525 1750) BN 16
J 0
(2513 1758);
DISPLAY 0.680851 (2513 1758);
PAINT GREEN (2513 1758);
FORCEPROP 2 LAST CDS_LIB standard
J 0
(2575 1750);
PAINT MONO (2575 1750);
DISPLAY INVISIBLE (2575 1750);
FORCEPROP 1 LAST BODY_TYPE PLUMBING
J 0
(2575 1800);
DISPLAY 0.872340 (2575 1800);
PAINT GREEN (2575 1800);
DISPLAY INVISIBLE (2575 1800);
FORCEPROP 1 LAST HDL_TAP TRUE
J 0
(2900 1625);
DISPLAY 0.872340 (2900 1625);
DISPLAY INVISIBLE (2900 1625);
FORCEPROP 1 LAST PATH I59
J 0
(2573 1750);
DISPLAY 0.872340 (2573 1750);
PAINT GREEN (2573 1750);
DISPLAY INVISIBLE (2573 1750);
FORCEADD TAP..1
R 2
(-1000 1550);
FORCEPROP 3 LASTPIN (-950 1550) SIG_NAME UPI_CPU1_CPU0_P2P2_DN<20>
J 0
(-940 1560);
DISPLAY 0.659574 (-940 1560);
PAINT MONO (-940 1560);
DISPLAY INVISIBLE (-940 1560);
FORCEPROP 1 LASTPIN (-950 1550) BN 20
J 2
(-938 1558);
DISPLAY 0.680851 (-938 1558);
PAINT GREEN (-938 1558);
FORCEPROP 2 LAST CDS_LIB standard
J 0
(-1000 1550);
DISPLAY INVISIBLE (-1000 1550);
FORCEPROP 1 LAST BODY_TYPE PLUMBING
J 2
(-1000 1600);
DISPLAY 0.872340 (-1000 1600);
PAINT GREEN (-1000 1600);
DISPLAY INVISIBLE (-1000 1600);
FORCEPROP 1 LAST HDL_TAP TRUE
J 2
(-1325 1425);
DISPLAY 0.872340 (-1325 1425);
DISPLAY INVISIBLE (-1325 1425);
FORCEPROP 1 LAST PATH I6
J 2
(-998 1550);
DISPLAY 0.872340 (-998 1550);
PAINT GREEN (-998 1550);
DISPLAY INVISIBLE (-998 1550);
FORCEADD TAP..1
(2575 1800);
FORCEPROP 3 LASTPIN (2525 1800) SIG_NAME UPI_CPU0_CPU1_P2P2_DN<15>
J 0
(2535 1810);
DISPLAY 0.659574 (2535 1810);
PAINT MONO (2535 1810);
DISPLAY INVISIBLE (2535 1810);
FORCEPROP 1 LASTPIN (2525 1800) BN 15
J 0
(2513 1808);
DISPLAY 0.680851 (2513 1808);
PAINT GREEN (2513 1808);
FORCEPROP 2 LAST CDS_LIB standard
J 0
(2575 1800);
PAINT MONO (2575 1800);
DISPLAY INVISIBLE (2575 1800);
FORCEPROP 1 LAST BODY_TYPE PLUMBING
J 0
(2575 1850);
DISPLAY 0.872340 (2575 1850);
PAINT GREEN (2575 1850);
DISPLAY INVISIBLE (2575 1850);
FORCEPROP 1 LAST HDL_TAP TRUE
J 0
(2900 1675);
DISPLAY 0.872340 (2900 1675);
DISPLAY INVISIBLE (2900 1675);
FORCEPROP 1 LAST PATH I60
J 0
(2573 1800);
DISPLAY 0.872340 (2573 1800);
PAINT GREEN (2573 1800);
DISPLAY INVISIBLE (2573 1800);
FORCEADD TAP..1
(2575 1900);
FORCEPROP 3 LASTPIN (2525 1900) SIG_NAME UPI_CPU0_CPU1_P2P2_DN<13>
J 0
(2535 1910);
DISPLAY 0.659574 (2535 1910);
PAINT MONO (2535 1910);
DISPLAY INVISIBLE (2535 1910);
FORCEPROP 1 LASTPIN (2525 1900) BN 13
J 0
(2513 1908);
DISPLAY 0.680851 (2513 1908);
PAINT GREEN (2513 1908);
FORCEPROP 2 LAST CDS_LIB standard
J 0
(2575 1900);
PAINT MONO (2575 1900);
DISPLAY INVISIBLE (2575 1900);
FORCEPROP 1 LAST BODY_TYPE PLUMBING
J 0
(2575 1950);
DISPLAY 0.872340 (2575 1950);
PAINT GREEN (2575 1950);
DISPLAY INVISIBLE (2575 1950);
FORCEPROP 1 LAST HDL_TAP TRUE
J 0
(2900 1775);
DISPLAY 0.872340 (2900 1775);
DISPLAY INVISIBLE (2900 1775);
FORCEPROP 1 LAST PATH I61
J 0
(2573 1900);
DISPLAY 0.872340 (2573 1900);
PAINT GREEN (2573 1900);
DISPLAY INVISIBLE (2573 1900);
FORCEADD TAP..1
(2575 1850);
FORCEPROP 3 LASTPIN (2525 1850) SIG_NAME UPI_CPU0_CPU1_P2P2_DN<14>
J 0
(2535 1860);
DISPLAY 0.659574 (2535 1860);
PAINT MONO (2535 1860);
DISPLAY INVISIBLE (2535 1860);
FORCEPROP 1 LASTPIN (2525 1850) BN 14
J 0
(2513 1858);
DISPLAY 0.680851 (2513 1858);
PAINT GREEN (2513 1858);
FORCEPROP 2 LAST CDS_LIB standard
J 0
(2575 1850);
PAINT MONO (2575 1850);
DISPLAY INVISIBLE (2575 1850);
FORCEPROP 1 LAST BODY_TYPE PLUMBING
J 0
(2575 1900);
DISPLAY 0.872340 (2575 1900);
PAINT GREEN (2575 1900);
DISPLAY INVISIBLE (2575 1900);
FORCEPROP 1 LAST HDL_TAP TRUE
J 0
(2900 1725);
DISPLAY 0.872340 (2900 1725);
DISPLAY INVISIBLE (2900 1725);
FORCEPROP 1 LAST PATH I62
J 0
(2573 1850);
DISPLAY 0.872340 (2573 1850);
PAINT GREEN (2573 1850);
DISPLAY INVISIBLE (2573 1850);
FORCEADD TAP..1
(2575 2000);
FORCEPROP 3 LASTPIN (2525 2000) SIG_NAME UPI_CPU0_CPU1_P2P2_DN<11>
J 0
(2535 2010);
DISPLAY 0.659574 (2535 2010);
PAINT MONO (2535 2010);
DISPLAY INVISIBLE (2535 2010);
FORCEPROP 1 LASTPIN (2525 2000) BN 11
J 0
(2513 2008);
DISPLAY 0.680851 (2513 2008);
PAINT GREEN (2513 2008);
FORCEPROP 2 LAST CDS_LIB standard
J 0
(2575 2000);
PAINT MONO (2575 2000);
DISPLAY INVISIBLE (2575 2000);
FORCEPROP 1 LAST BODY_TYPE PLUMBING
J 0
(2575 2050);
DISPLAY 0.872340 (2575 2050);
PAINT GREEN (2575 2050);
DISPLAY INVISIBLE (2575 2050);
FORCEPROP 1 LAST HDL_TAP TRUE
J 0
(2900 1875);
DISPLAY 0.872340 (2900 1875);
DISPLAY INVISIBLE (2900 1875);
FORCEPROP 1 LAST PATH I63
J 0
(2573 2000);
DISPLAY 0.872340 (2573 2000);
PAINT GREEN (2573 2000);
DISPLAY INVISIBLE (2573 2000);
FORCEADD TAP..1
(2575 1950);
FORCEPROP 3 LASTPIN (2525 1950) SIG_NAME UPI_CPU0_CPU1_P2P2_DN<12>
J 0
(2535 1960);
DISPLAY 0.659574 (2535 1960);
PAINT MONO (2535 1960);
DISPLAY INVISIBLE (2535 1960);
FORCEPROP 1 LASTPIN (2525 1950) BN 12
J 0
(2513 1958);
DISPLAY 0.680851 (2513 1958);
PAINT GREEN (2513 1958);
FORCEPROP 2 LAST CDS_LIB standard
J 0
(2575 1950);
PAINT MONO (2575 1950);
DISPLAY INVISIBLE (2575 1950);
FORCEPROP 1 LAST BODY_TYPE PLUMBING
J 0
(2575 2000);
DISPLAY 0.872340 (2575 2000);
PAINT GREEN (2575 2000);
DISPLAY INVISIBLE (2575 2000);
FORCEPROP 1 LAST HDL_TAP TRUE
J 0
(2900 1825);
DISPLAY 0.872340 (2900 1825);
DISPLAY INVISIBLE (2900 1825);
FORCEPROP 1 LAST PATH I64
J 0
(2573 1950);
DISPLAY 0.872340 (2573 1950);
PAINT GREEN (2573 1950);
DISPLAY INVISIBLE (2573 1950);
FORCEADD TAP..1
(2575 2050);
FORCEPROP 3 LASTPIN (2525 2050) SIG_NAME UPI_CPU0_CPU1_P2P2_DN<10>
J 0
(2535 2060);
DISPLAY 0.659574 (2535 2060);
PAINT MONO (2535 2060);
DISPLAY INVISIBLE (2535 2060);
FORCEPROP 1 LASTPIN (2525 2050) BN 10
J 0
(2513 2058);
DISPLAY 0.680851 (2513 2058);
PAINT GREEN (2513 2058);
FORCEPROP 2 LAST CDS_LIB standard
J 0
(2575 2050);
PAINT MONO (2575 2050);
DISPLAY INVISIBLE (2575 2050);
FORCEPROP 1 LAST BODY_TYPE PLUMBING
J 0
(2575 2100);
DISPLAY 0.872340 (2575 2100);
PAINT GREEN (2575 2100);
DISPLAY INVISIBLE (2575 2100);
FORCEPROP 1 LAST HDL_TAP TRUE
J 0
(2900 1925);
DISPLAY 0.872340 (2900 1925);
DISPLAY INVISIBLE (2900 1925);
FORCEPROP 1 LAST PATH I65
J 0
(2573 2050);
DISPLAY 0.872340 (2573 2050);
PAINT GREEN (2573 2050);
DISPLAY INVISIBLE (2573 2050);
FORCEADD TAP..1
(2575 2150);
FORCEPROP 3 LASTPIN (2525 2150) SIG_NAME UPI_CPU0_CPU1_P2P2_DN<8>
J 0
(2535 2160);
DISPLAY 0.659574 (2535 2160);
PAINT MONO (2535 2160);
DISPLAY INVISIBLE (2535 2160);
FORCEPROP 1 LASTPIN (2525 2150) BN 8
J 0
(2513 2158);
DISPLAY 0.680851 (2513 2158);
PAINT GREEN (2513 2158);
FORCEPROP 2 LAST CDS_LIB standard
J 0
(2575 2150);
PAINT MONO (2575 2150);
DISPLAY INVISIBLE (2575 2150);
FORCEPROP 1 LAST BODY_TYPE PLUMBING
J 0
(2575 2200);
DISPLAY 0.872340 (2575 2200);
PAINT GREEN (2575 2200);
DISPLAY INVISIBLE (2575 2200);
FORCEPROP 1 LAST HDL_TAP TRUE
J 0
(2900 2025);
DISPLAY 0.872340 (2900 2025);
DISPLAY INVISIBLE (2900 2025);
FORCEPROP 1 LAST PATH I66
J 0
(2573 2150);
DISPLAY 0.872340 (2573 2150);
PAINT GREEN (2573 2150);
DISPLAY INVISIBLE (2573 2150);
FORCEADD TAP..1
(2575 2100);
FORCEPROP 3 LASTPIN (2525 2100) SIG_NAME UPI_CPU0_CPU1_P2P2_DN<9>
J 0
(2535 2110);
DISPLAY 0.659574 (2535 2110);
PAINT MONO (2535 2110);
DISPLAY INVISIBLE (2535 2110);
FORCEPROP 1 LASTPIN (2525 2100) BN 9
J 0
(2513 2108);
DISPLAY 0.680851 (2513 2108);
PAINT GREEN (2513 2108);
FORCEPROP 2 LAST CDS_LIB standard
J 0
(2575 2100);
PAINT MONO (2575 2100);
DISPLAY INVISIBLE (2575 2100);
FORCEPROP 1 LAST BODY_TYPE PLUMBING
J 0
(2575 2150);
DISPLAY 0.872340 (2575 2150);
PAINT GREEN (2575 2150);
DISPLAY INVISIBLE (2575 2150);
FORCEPROP 1 LAST HDL_TAP TRUE
J 0
(2900 1975);
DISPLAY 0.872340 (2900 1975);
DISPLAY INVISIBLE (2900 1975);
FORCEPROP 1 LAST PATH I67
J 0
(2573 2100);
DISPLAY 0.872340 (2573 2100);
PAINT GREEN (2573 2100);
DISPLAY INVISIBLE (2573 2100);
FORCEADD TAP..1
(2575 2250);
FORCEPROP 3 LASTPIN (2525 2250) SIG_NAME UPI_CPU0_CPU1_P2P2_DN<6>
J 0
(2535 2260);
DISPLAY 0.659574 (2535 2260);
PAINT MONO (2535 2260);
DISPLAY INVISIBLE (2535 2260);
FORCEPROP 1 LASTPIN (2525 2250) BN 6
J 0
(2513 2258);
DISPLAY 0.680851 (2513 2258);
PAINT GREEN (2513 2258);
FORCEPROP 2 LAST CDS_LIB standard
J 0
(2575 2250);
DISPLAY INVISIBLE (2575 2250);
FORCEPROP 1 LAST BODY_TYPE PLUMBING
J 0
(2575 2300);
DISPLAY 0.872340 (2575 2300);
PAINT GREEN (2575 2300);
DISPLAY INVISIBLE (2575 2300);
FORCEPROP 1 LAST HDL_TAP TRUE
J 0
(2900 2125);
DISPLAY 0.872340 (2900 2125);
DISPLAY INVISIBLE (2900 2125);
FORCEPROP 1 LAST PATH I68
J 0
(2573 2250);
DISPLAY 0.872340 (2573 2250);
PAINT GREEN (2573 2250);
DISPLAY INVISIBLE (2573 2250);
FORCEADD TAP..1
(2575 2200);
FORCEPROP 3 LASTPIN (2525 2200) SIG_NAME UPI_CPU0_CPU1_P2P2_DN<7>
J 0
(2535 2210);
DISPLAY 0.659574 (2535 2210);
PAINT MONO (2535 2210);
DISPLAY INVISIBLE (2535 2210);
FORCEPROP 1 LASTPIN (2525 2200) BN 7
J 0
(2513 2208);
DISPLAY 0.680851 (2513 2208);
PAINT GREEN (2513 2208);
FORCEPROP 2 LAST CDS_LIB standard
J 0
(2575 2200);
PAINT MONO (2575 2200);
DISPLAY INVISIBLE (2575 2200);
FORCEPROP 1 LAST BODY_TYPE PLUMBING
J 0
(2575 2250);
DISPLAY 0.872340 (2575 2250);
PAINT GREEN (2575 2250);
DISPLAY INVISIBLE (2575 2250);
FORCEPROP 1 LAST HDL_TAP TRUE
J 0
(2900 2075);
DISPLAY 0.872340 (2900 2075);
DISPLAY INVISIBLE (2900 2075);
FORCEPROP 1 LAST PATH I69
J 0
(2573 2200);
DISPLAY 0.872340 (2573 2200);
PAINT GREEN (2573 2200);
DISPLAY INVISIBLE (2573 2200);
FORCEADD TAP..1
R 2
(-1000 1600);
FORCEPROP 3 LASTPIN (-950 1600) SIG_NAME UPI_CPU1_CPU0_P2P2_DN<19>
J 0
(-940 1610);
DISPLAY 0.659574 (-940 1610);
PAINT MONO (-940 1610);
DISPLAY INVISIBLE (-940 1610);
FORCEPROP 1 LASTPIN (-950 1600) BN 19
J 2
(-938 1608);
DISPLAY 0.680851 (-938 1608);
PAINT GREEN (-938 1608);
FORCEPROP 2 LAST CDS_LIB standard
J 0
(-1000 1600);
DISPLAY INVISIBLE (-1000 1600);
FORCEPROP 1 LAST BODY_TYPE PLUMBING
J 2
(-1000 1650);
DISPLAY 0.872340 (-1000 1650);
PAINT GREEN (-1000 1650);
DISPLAY INVISIBLE (-1000 1650);
FORCEPROP 1 LAST HDL_TAP TRUE
J 2
(-1325 1475);
DISPLAY 0.872340 (-1325 1475);
DISPLAY INVISIBLE (-1325 1475);
FORCEPROP 1 LAST PATH I7
J 2
(-998 1600);
DISPLAY 0.872340 (-998 1600);
PAINT GREEN (-998 1600);
DISPLAY INVISIBLE (-998 1600);
FORCEADD TAP..1
(2575 2350);
FORCEPROP 3 LASTPIN (2525 2350) SIG_NAME UPI_CPU0_CPU1_P2P2_DN<4>
J 0
(2535 2360);
DISPLAY 0.659574 (2535 2360);
PAINT MONO (2535 2360);
DISPLAY INVISIBLE (2535 2360);
FORCEPROP 1 LASTPIN (2525 2350) BN 4
J 0
(2513 2358);
DISPLAY 0.680851 (2513 2358);
PAINT GREEN (2513 2358);
FORCEPROP 2 LAST CDS_LIB standard
J 0
(2575 2350);
DISPLAY INVISIBLE (2575 2350);
FORCEPROP 1 LAST BODY_TYPE PLUMBING
J 0
(2575 2400);
DISPLAY 0.872340 (2575 2400);
PAINT GREEN (2575 2400);
DISPLAY INVISIBLE (2575 2400);
FORCEPROP 1 LAST HDL_TAP TRUE
J 0
(2900 2225);
DISPLAY 0.872340 (2900 2225);
DISPLAY INVISIBLE (2900 2225);
FORCEPROP 1 LAST PATH I70
J 0
(2573 2350);
DISPLAY 0.872340 (2573 2350);
PAINT GREEN (2573 2350);
DISPLAY INVISIBLE (2573 2350);
FORCEADD TAP..1
(2575 2300);
FORCEPROP 3 LASTPIN (2525 2300) SIG_NAME UPI_CPU0_CPU1_P2P2_DN<5>
J 0
(2535 2310);
DISPLAY 0.659574 (2535 2310);
PAINT MONO (2535 2310);
DISPLAY INVISIBLE (2535 2310);
FORCEPROP 1 LASTPIN (2525 2300) BN 5
J 0
(2513 2308);
DISPLAY 0.680851 (2513 2308);
PAINT GREEN (2513 2308);
FORCEPROP 2 LAST CDS_LIB standard
J 0
(2575 2300);
DISPLAY INVISIBLE (2575 2300);
FORCEPROP 1 LAST BODY_TYPE PLUMBING
J 0
(2575 2350);
DISPLAY 0.872340 (2575 2350);
PAINT GREEN (2575 2350);
DISPLAY INVISIBLE (2575 2350);
FORCEPROP 1 LAST HDL_TAP TRUE
J 0
(2900 2175);
DISPLAY 0.872340 (2900 2175);
DISPLAY INVISIBLE (2900 2175);
FORCEPROP 1 LAST PATH I71
J 0
(2573 2300);
DISPLAY 0.872340 (2573 2300);
PAINT GREEN (2573 2300);
DISPLAY INVISIBLE (2573 2300);
FORCEADD TAP..1
(2575 2400);
FORCEPROP 3 LASTPIN (2525 2400) SIG_NAME UPI_CPU0_CPU1_P2P2_DN<3>
J 0
(2535 2410);
DISPLAY 0.659574 (2535 2410);
PAINT MONO (2535 2410);
DISPLAY INVISIBLE (2535 2410);
FORCEPROP 1 LASTPIN (2525 2400) BN 3
J 0
(2513 2408);
DISPLAY 0.680851 (2513 2408);
PAINT GREEN (2513 2408);
FORCEPROP 2 LAST CDS_LIB standard
J 0
(2575 2400);
DISPLAY INVISIBLE (2575 2400);
FORCEPROP 1 LAST BODY_TYPE PLUMBING
J 0
(2575 2450);
DISPLAY 0.872340 (2575 2450);
PAINT GREEN (2575 2450);
DISPLAY INVISIBLE (2575 2450);
FORCEPROP 1 LAST HDL_TAP TRUE
J 0
(2900 2275);
DISPLAY 0.872340 (2900 2275);
DISPLAY INVISIBLE (2900 2275);
FORCEPROP 1 LAST PATH I72
J 0
(2573 2400);
DISPLAY 0.872340 (2573 2400);
PAINT GREEN (2573 2400);
DISPLAY INVISIBLE (2573 2400);
FORCEADD TAP..1
(2575 2450);
FORCEPROP 3 LASTPIN (2525 2450) SIG_NAME UPI_CPU0_CPU1_P2P2_DN<2>
J 0
(2535 2460);
DISPLAY 0.659574 (2535 2460);
PAINT MONO (2535 2460);
DISPLAY INVISIBLE (2535 2460);
FORCEPROP 1 LASTPIN (2525 2450) BN 2
J 0
(2513 2458);
DISPLAY 0.680851 (2513 2458);
PAINT GREEN (2513 2458);
FORCEPROP 2 LAST CDS_LIB standard
J 0
(2575 2450);
DISPLAY INVISIBLE (2575 2450);
FORCEPROP 1 LAST BODY_TYPE PLUMBING
J 0
(2575 2500);
DISPLAY 0.872340 (2575 2500);
PAINT GREEN (2575 2500);
DISPLAY INVISIBLE (2575 2500);
FORCEPROP 1 LAST HDL_TAP TRUE
J 0
(2900 2325);
DISPLAY 0.872340 (2900 2325);
DISPLAY INVISIBLE (2900 2325);
FORCEPROP 1 LAST PATH I73
J 0
(2573 2450);
DISPLAY 0.872340 (2573 2450);
PAINT GREEN (2573 2450);
DISPLAY INVISIBLE (2573 2450);
FORCEADD TAP..1
(2575 2500);
FORCEPROP 3 LASTPIN (2525 2500) SIG_NAME UPI_CPU0_CPU1_P2P2_DN<1>
J 0
(2535 2510);
DISPLAY 0.659574 (2535 2510);
PAINT MONO (2535 2510);
DISPLAY INVISIBLE (2535 2510);
FORCEPROP 1 LASTPIN (2525 2500) BN 1
J 0
(2513 2508);
DISPLAY 0.680851 (2513 2508);
PAINT GREEN (2513 2508);
FORCEPROP 2 LAST CDS_LIB standard
J 0
(2575 2500);
DISPLAY INVISIBLE (2575 2500);
FORCEPROP 1 LAST BODY_TYPE PLUMBING
J 0
(2575 2550);
DISPLAY 0.872340 (2575 2550);
PAINT GREEN (2575 2550);
DISPLAY INVISIBLE (2575 2550);
FORCEPROP 1 LAST HDL_TAP TRUE
J 0
(2900 2375);
DISPLAY 0.872340 (2900 2375);
DISPLAY INVISIBLE (2900 2375);
FORCEPROP 1 LAST PATH I74
J 0
(2573 2500);
DISPLAY 0.872340 (2573 2500);
PAINT GREEN (2573 2500);
DISPLAY INVISIBLE (2573 2500);
FORCEADD TAP..1
(2575 2750);
FORCEPROP 3 LASTPIN (2525 2750) SIG_NAME UPI_CPU0_CPU1_P2P2_DP<21>
J 0
(2535 2760);
DISPLAY 0.659574 (2535 2760);
PAINT MONO (2535 2760);
DISPLAY INVISIBLE (2535 2760);
FORCEPROP 1 LASTPIN (2525 2750) BN 21
J 0
(2513 2758);
DISPLAY 0.680851 (2513 2758);
PAINT GREEN (2513 2758);
FORCEPROP 2 LAST CDS_LIB standard
J 0
(2575 2750);
PAINT MONO (2575 2750);
DISPLAY INVISIBLE (2575 2750);
FORCEPROP 1 LAST BODY_TYPE PLUMBING
J 0
(2575 2800);
DISPLAY 0.872340 (2575 2800);
PAINT GREEN (2575 2800);
DISPLAY INVISIBLE (2575 2800);
FORCEPROP 1 LAST HDL_TAP TRUE
J 0
(2900 2625);
DISPLAY 0.872340 (2900 2625);
DISPLAY INVISIBLE (2900 2625);
FORCEPROP 1 LAST PATH I75
J 0
(2573 2750);
DISPLAY 0.872340 (2573 2750);
PAINT GREEN (2573 2750);
DISPLAY INVISIBLE (2573 2750);
FORCEADD TAP..1
(2575 2650);
FORCEPROP 3 LASTPIN (2525 2650) SIG_NAME UPI_CPU0_CPU1_P2P2_DP<23>
J 0
(2535 2660);
DISPLAY 0.659574 (2535 2660);
PAINT MONO (2535 2660);
DISPLAY INVISIBLE (2535 2660);
FORCEPROP 1 LASTPIN (2525 2650) BN 23
J 0
(2513 2658);
DISPLAY 0.680851 (2513 2658);
PAINT GREEN (2513 2658);
FORCEPROP 2 LAST CDS_LIB standard
J 0
(2575 2650);
PAINT MONO (2575 2650);
DISPLAY INVISIBLE (2575 2650);
FORCEPROP 1 LAST BODY_TYPE PLUMBING
J 0
(2575 2700);
DISPLAY 0.872340 (2575 2700);
PAINT GREEN (2575 2700);
DISPLAY INVISIBLE (2575 2700);
FORCEPROP 1 LAST HDL_TAP TRUE
J 0
(2900 2525);
DISPLAY 0.872340 (2900 2525);
DISPLAY INVISIBLE (2900 2525);
FORCEPROP 1 LAST PATH I76
J 0
(2573 2650);
DISPLAY 0.872340 (2573 2650);
PAINT GREEN (2573 2650);
DISPLAY INVISIBLE (2573 2650);
FORCEADD TAP..1
(2575 2550);
FORCEPROP 3 LASTPIN (2525 2550) SIG_NAME UPI_CPU0_CPU1_P2P2_DN<0>
J 0
(2535 2560);
DISPLAY 0.659574 (2535 2560);
PAINT MONO (2535 2560);
DISPLAY INVISIBLE (2535 2560);
FORCEPROP 1 LASTPIN (2525 2550) BN 0
J 0
(2513 2558);
DISPLAY 0.680851 (2513 2558);
PAINT GREEN (2513 2558);
FORCEPROP 2 LAST CDS_LIB standard
J 0
(2575 2550);
DISPLAY INVISIBLE (2575 2550);
FORCEPROP 1 LAST BODY_TYPE PLUMBING
J 0
(2575 2600);
DISPLAY 0.872340 (2575 2600);
PAINT GREEN (2575 2600);
DISPLAY INVISIBLE (2575 2600);
FORCEPROP 1 LAST HDL_TAP TRUE
J 0
(2900 2425);
DISPLAY 0.872340 (2900 2425);
DISPLAY INVISIBLE (2900 2425);
FORCEPROP 1 LAST PATH I77
J 0
(2573 2550);
DISPLAY 0.872340 (2573 2550);
PAINT GREEN (2573 2550);
DISPLAY INVISIBLE (2573 2550);
FORCEADD TAP..1
(2575 2700);
FORCEPROP 3 LASTPIN (2525 2700) SIG_NAME UPI_CPU0_CPU1_P2P2_DP<22>
J 0
(2535 2710);
DISPLAY 0.659574 (2535 2710);
PAINT MONO (2535 2710);
DISPLAY INVISIBLE (2535 2710);
FORCEPROP 1 LASTPIN (2525 2700) BN 22
J 0
(2513 2708);
DISPLAY 0.680851 (2513 2708);
PAINT GREEN (2513 2708);
FORCEPROP 2 LAST CDS_LIB standard
J 0
(2575 2700);
PAINT MONO (2575 2700);
DISPLAY INVISIBLE (2575 2700);
FORCEPROP 1 LAST BODY_TYPE PLUMBING
J 0
(2575 2750);
DISPLAY 0.872340 (2575 2750);
PAINT GREEN (2575 2750);
DISPLAY INVISIBLE (2575 2750);
FORCEPROP 1 LAST HDL_TAP TRUE
J 0
(2900 2575);
DISPLAY 0.872340 (2900 2575);
DISPLAY INVISIBLE (2900 2575);
FORCEPROP 1 LAST PATH I78
J 0
(2573 2700);
DISPLAY 0.872340 (2573 2700);
PAINT GREEN (2573 2700);
DISPLAY INVISIBLE (2573 2700);
FORCEADD TAP..1
(2575 2800);
FORCEPROP 3 LASTPIN (2525 2800) SIG_NAME UPI_CPU0_CPU1_P2P2_DP<20>
J 0
(2535 2810);
DISPLAY 0.659574 (2535 2810);
PAINT MONO (2535 2810);
DISPLAY INVISIBLE (2535 2810);
FORCEPROP 1 LASTPIN (2525 2800) BN 20
J 0
(2513 2808);
DISPLAY 0.680851 (2513 2808);
PAINT GREEN (2513 2808);
FORCEPROP 2 LAST CDS_LIB standard
J 0
(2575 2800);
PAINT MONO (2575 2800);
DISPLAY INVISIBLE (2575 2800);
FORCEPROP 1 LAST BODY_TYPE PLUMBING
J 0
(2575 2850);
DISPLAY 0.872340 (2575 2850);
PAINT GREEN (2575 2850);
DISPLAY INVISIBLE (2575 2850);
FORCEPROP 1 LAST HDL_TAP TRUE
J 0
(2900 2675);
DISPLAY 0.872340 (2900 2675);
DISPLAY INVISIBLE (2900 2675);
FORCEPROP 1 LAST PATH I79
J 0
(2573 2800);
DISPLAY 0.872340 (2573 2800);
PAINT GREEN (2573 2800);
DISPLAY INVISIBLE (2573 2800);
FORCEADD TAP..1
R 2
(-1000 1650);
FORCEPROP 3 LASTPIN (-950 1650) SIG_NAME UPI_CPU1_CPU0_P2P2_DN<18>
J 0
(-940 1660);
DISPLAY 0.659574 (-940 1660);
PAINT MONO (-940 1660);
DISPLAY INVISIBLE (-940 1660);
FORCEPROP 1 LASTPIN (-950 1650) BN 18
J 2
(-938 1658);
DISPLAY 0.680851 (-938 1658);
PAINT GREEN (-938 1658);
FORCEPROP 2 LAST CDS_LIB standard
J 0
(-1000 1650);
DISPLAY INVISIBLE (-1000 1650);
FORCEPROP 1 LAST BODY_TYPE PLUMBING
J 2
(-1000 1700);
DISPLAY 0.872340 (-1000 1700);
PAINT GREEN (-1000 1700);
DISPLAY INVISIBLE (-1000 1700);
FORCEPROP 1 LAST HDL_TAP TRUE
J 2
(-1325 1525);
DISPLAY 0.872340 (-1325 1525);
DISPLAY INVISIBLE (-1325 1525);
FORCEPROP 1 LAST PATH I8
J 2
(-998 1650);
DISPLAY 0.872340 (-998 1650);
PAINT GREEN (-998 1650);
DISPLAY INVISIBLE (-998 1650);
FORCEADD TAP..1
(2575 2900);
FORCEPROP 3 LASTPIN (2525 2900) SIG_NAME UPI_CPU0_CPU1_P2P2_DP<18>
J 0
(2535 2910);
DISPLAY 0.659574 (2535 2910);
PAINT MONO (2535 2910);
DISPLAY INVISIBLE (2535 2910);
FORCEPROP 1 LASTPIN (2525 2900) BN 18
J 0
(2513 2908);
DISPLAY 0.680851 (2513 2908);
PAINT GREEN (2513 2908);
FORCEPROP 2 LAST CDS_LIB standard
J 0
(2575 2900);
PAINT MONO (2575 2900);
DISPLAY INVISIBLE (2575 2900);
FORCEPROP 1 LAST BODY_TYPE PLUMBING
J 0
(2575 2950);
DISPLAY 0.872340 (2575 2950);
PAINT GREEN (2575 2950);
DISPLAY INVISIBLE (2575 2950);
FORCEPROP 1 LAST HDL_TAP TRUE
J 0
(2900 2775);
DISPLAY 0.872340 (2900 2775);
DISPLAY INVISIBLE (2900 2775);
FORCEPROP 1 LAST PATH I80
J 0
(2573 2900);
DISPLAY 0.872340 (2573 2900);
PAINT GREEN (2573 2900);
DISPLAY INVISIBLE (2573 2900);
FORCEADD TAP..1
(2575 2850);
FORCEPROP 3 LASTPIN (2525 2850) SIG_NAME UPI_CPU0_CPU1_P2P2_DP<19>
J 0
(2535 2860);
DISPLAY 0.659574 (2535 2860);
PAINT MONO (2535 2860);
DISPLAY INVISIBLE (2535 2860);
FORCEPROP 1 LASTPIN (2525 2850) BN 19
J 0
(2513 2858);
DISPLAY 0.680851 (2513 2858);
PAINT GREEN (2513 2858);
FORCEPROP 2 LAST CDS_LIB standard
J 0
(2575 2850);
PAINT MONO (2575 2850);
DISPLAY INVISIBLE (2575 2850);
FORCEPROP 1 LAST BODY_TYPE PLUMBING
J 0
(2575 2900);
DISPLAY 0.872340 (2575 2900);
PAINT GREEN (2575 2900);
DISPLAY INVISIBLE (2575 2900);
FORCEPROP 1 LAST HDL_TAP TRUE
J 0
(2900 2725);
DISPLAY 0.872340 (2900 2725);
DISPLAY INVISIBLE (2900 2725);
FORCEPROP 1 LAST PATH I81
J 0
(2573 2850);
DISPLAY 0.872340 (2573 2850);
PAINT GREEN (2573 2850);
DISPLAY INVISIBLE (2573 2850);
FORCEADD TAP..1
(2575 3000);
FORCEPROP 3 LASTPIN (2525 3000) SIG_NAME UPI_CPU0_CPU1_P2P2_DP<16>
J 0
(2535 3010);
DISPLAY 0.659574 (2535 3010);
PAINT MONO (2535 3010);
DISPLAY INVISIBLE (2535 3010);
FORCEPROP 1 LASTPIN (2525 3000) BN 16
J 0
(2513 3008);
DISPLAY 0.680851 (2513 3008);
PAINT GREEN (2513 3008);
FORCEPROP 2 LAST CDS_LIB standard
J 0
(2575 3000);
PAINT MONO (2575 3000);
DISPLAY INVISIBLE (2575 3000);
FORCEPROP 1 LAST BODY_TYPE PLUMBING
J 0
(2575 3050);
DISPLAY 0.872340 (2575 3050);
PAINT GREEN (2575 3050);
DISPLAY INVISIBLE (2575 3050);
FORCEPROP 1 LAST HDL_TAP TRUE
J 0
(2900 2875);
DISPLAY 0.872340 (2900 2875);
DISPLAY INVISIBLE (2900 2875);
FORCEPROP 1 LAST PATH I82
J 0
(2573 3000);
DISPLAY 0.872340 (2573 3000);
PAINT GREEN (2573 3000);
DISPLAY INVISIBLE (2573 3000);
FORCEADD TAP..1
(2575 2950);
FORCEPROP 3 LASTPIN (2525 2950) SIG_NAME UPI_CPU0_CPU1_P2P2_DP<17>
J 0
(2535 2960);
DISPLAY 0.659574 (2535 2960);
PAINT MONO (2535 2960);
DISPLAY INVISIBLE (2535 2960);
FORCEPROP 1 LASTPIN (2525 2950) BN 17
J 0
(2513 2958);
DISPLAY 0.680851 (2513 2958);
PAINT GREEN (2513 2958);
FORCEPROP 2 LAST CDS_LIB standard
J 0
(2575 2950);
PAINT MONO (2575 2950);
DISPLAY INVISIBLE (2575 2950);
FORCEPROP 1 LAST BODY_TYPE PLUMBING
J 0
(2575 3000);
DISPLAY 0.872340 (2575 3000);
PAINT GREEN (2575 3000);
DISPLAY INVISIBLE (2575 3000);
FORCEPROP 1 LAST HDL_TAP TRUE
J 0
(2900 2825);
DISPLAY 0.872340 (2900 2825);
DISPLAY INVISIBLE (2900 2825);
FORCEPROP 1 LAST PATH I83
J 0
(2573 2950);
DISPLAY 0.872340 (2573 2950);
PAINT GREEN (2573 2950);
DISPLAY INVISIBLE (2573 2950);
FORCEADD TAP..1
(2575 3150);
FORCEPROP 3 LASTPIN (2525 3150) SIG_NAME UPI_CPU0_CPU1_P2P2_DP<13>
J 0
(2535 3160);
DISPLAY 0.659574 (2535 3160);
PAINT MONO (2535 3160);
DISPLAY INVISIBLE (2535 3160);
FORCEPROP 1 LASTPIN (2525 3150) BN 13
J 0
(2513 3158);
DISPLAY 0.680851 (2513 3158);
PAINT GREEN (2513 3158);
FORCEPROP 2 LAST CDS_LIB standard
J 0
(2575 3150);
PAINT MONO (2575 3150);
DISPLAY INVISIBLE (2575 3150);
FORCEPROP 1 LAST BODY_TYPE PLUMBING
J 0
(2575 3200);
DISPLAY 0.872340 (2575 3200);
PAINT GREEN (2575 3200);
DISPLAY INVISIBLE (2575 3200);
FORCEPROP 1 LAST HDL_TAP TRUE
J 0
(2900 3025);
DISPLAY 0.872340 (2900 3025);
DISPLAY INVISIBLE (2900 3025);
FORCEPROP 1 LAST PATH I84
J 0
(2573 3150);
DISPLAY 0.872340 (2573 3150);
PAINT GREEN (2573 3150);
DISPLAY INVISIBLE (2573 3150);
FORCEADD TAP..1
(2575 3100);
FORCEPROP 3 LASTPIN (2525 3100) SIG_NAME UPI_CPU0_CPU1_P2P2_DP<14>
J 0
(2535 3110);
DISPLAY 0.659574 (2535 3110);
PAINT MONO (2535 3110);
DISPLAY INVISIBLE (2535 3110);
FORCEPROP 1 LASTPIN (2525 3100) BN 14
J 0
(2513 3108);
DISPLAY 0.680851 (2513 3108);
PAINT GREEN (2513 3108);
FORCEPROP 2 LAST CDS_LIB standard
J 0
(2575 3100);
PAINT MONO (2575 3100);
DISPLAY INVISIBLE (2575 3100);
FORCEPROP 1 LAST BODY_TYPE PLUMBING
J 0
(2575 3150);
DISPLAY 0.872340 (2575 3150);
PAINT GREEN (2575 3150);
DISPLAY INVISIBLE (2575 3150);
FORCEPROP 1 LAST HDL_TAP TRUE
J 0
(2900 2975);
DISPLAY 0.872340 (2900 2975);
DISPLAY INVISIBLE (2900 2975);
FORCEPROP 1 LAST PATH I85
J 0
(2573 3100);
DISPLAY 0.872340 (2573 3100);
PAINT GREEN (2573 3100);
DISPLAY INVISIBLE (2573 3100);
FORCEADD TAP..1
(2575 3050);
FORCEPROP 3 LASTPIN (2525 3050) SIG_NAME UPI_CPU0_CPU1_P2P2_DP<15>
J 0
(2535 3060);
DISPLAY 0.659574 (2535 3060);
PAINT MONO (2535 3060);
DISPLAY INVISIBLE (2535 3060);
FORCEPROP 1 LASTPIN (2525 3050) BN 15
J 0
(2513 3058);
DISPLAY 0.680851 (2513 3058);
PAINT GREEN (2513 3058);
FORCEPROP 2 LAST CDS_LIB standard
J 0
(2575 3050);
PAINT MONO (2575 3050);
DISPLAY INVISIBLE (2575 3050);
FORCEPROP 1 LAST BODY_TYPE PLUMBING
J 0
(2575 3100);
DISPLAY 0.872340 (2575 3100);
PAINT GREEN (2575 3100);
DISPLAY INVISIBLE (2575 3100);
FORCEPROP 1 LAST HDL_TAP TRUE
J 0
(2900 2925);
DISPLAY 0.872340 (2900 2925);
DISPLAY INVISIBLE (2900 2925);
FORCEPROP 1 LAST PATH I86
J 0
(2573 3050);
DISPLAY 0.872340 (2573 3050);
PAINT GREEN (2573 3050);
DISPLAY INVISIBLE (2573 3050);
FORCEADD TAP..1
(2575 3200);
FORCEPROP 3 LASTPIN (2525 3200) SIG_NAME UPI_CPU0_CPU1_P2P2_DP<12>
J 0
(2535 3210);
DISPLAY 0.659574 (2535 3210);
PAINT MONO (2535 3210);
DISPLAY INVISIBLE (2535 3210);
FORCEPROP 1 LASTPIN (2525 3200) BN 12
J 0
(2513 3208);
DISPLAY 0.680851 (2513 3208);
PAINT GREEN (2513 3208);
FORCEPROP 2 LAST CDS_LIB standard
J 0
(2575 3200);
PAINT MONO (2575 3200);
DISPLAY INVISIBLE (2575 3200);
FORCEPROP 1 LAST BODY_TYPE PLUMBING
J 0
(2575 3250);
DISPLAY 0.872340 (2575 3250);
PAINT GREEN (2575 3250);
DISPLAY INVISIBLE (2575 3250);
FORCEPROP 1 LAST HDL_TAP TRUE
J 0
(2900 3075);
DISPLAY 0.872340 (2900 3075);
DISPLAY INVISIBLE (2900 3075);
FORCEPROP 1 LAST PATH I87
J 0
(2573 3200);
DISPLAY 0.872340 (2573 3200);
PAINT GREEN (2573 3200);
DISPLAY INVISIBLE (2573 3200);
FORCEADD TAP..1
(2575 3250);
FORCEPROP 3 LASTPIN (2525 3250) SIG_NAME UPI_CPU0_CPU1_P2P2_DP<11>
J 0
(2535 3260);
DISPLAY 0.659574 (2535 3260);
PAINT MONO (2535 3260);
DISPLAY INVISIBLE (2535 3260);
FORCEPROP 1 LASTPIN (2525 3250) BN 11
J 0
(2513 3258);
DISPLAY 0.680851 (2513 3258);
PAINT GREEN (2513 3258);
FORCEPROP 2 LAST CDS_LIB standard
J 0
(2575 3250);
PAINT MONO (2575 3250);
DISPLAY INVISIBLE (2575 3250);
FORCEPROP 1 LAST BODY_TYPE PLUMBING
J 0
(2575 3300);
DISPLAY 0.872340 (2575 3300);
PAINT GREEN (2575 3300);
DISPLAY INVISIBLE (2575 3300);
FORCEPROP 1 LAST HDL_TAP TRUE
J 0
(2900 3125);
DISPLAY 0.872340 (2900 3125);
DISPLAY INVISIBLE (2900 3125);
FORCEPROP 1 LAST PATH I88
J 0
(2573 3250);
DISPLAY 0.872340 (2573 3250);
PAINT GREEN (2573 3250);
DISPLAY INVISIBLE (2573 3250);
FORCEADD TAP..1
(2575 3500);
FORCEPROP 3 LASTPIN (2525 3500) SIG_NAME UPI_CPU0_CPU1_P2P2_DP<6>
J 0
(2535 3510);
DISPLAY 0.659574 (2535 3510);
PAINT MONO (2535 3510);
DISPLAY INVISIBLE (2535 3510);
FORCEPROP 1 LASTPIN (2525 3500) BN 6
J 0
(2513 3508);
DISPLAY 0.680851 (2513 3508);
PAINT GREEN (2513 3508);
FORCEPROP 2 LAST CDS_LIB standard
J 0
(2575 3500);
DISPLAY INVISIBLE (2575 3500);
FORCEPROP 1 LAST BODY_TYPE PLUMBING
J 0
(2575 3550);
DISPLAY 0.872340 (2575 3550);
PAINT GREEN (2575 3550);
DISPLAY INVISIBLE (2575 3550);
FORCEPROP 1 LAST HDL_TAP TRUE
J 0
(2900 3375);
DISPLAY 0.872340 (2900 3375);
DISPLAY INVISIBLE (2900 3375);
FORCEPROP 1 LAST PATH I89
J 0
(2573 3500);
DISPLAY 0.872340 (2573 3500);
PAINT GREEN (2573 3500);
DISPLAY INVISIBLE (2573 3500);
FORCEADD TAP..1
R 2
(-1000 1700);
FORCEPROP 3 LASTPIN (-950 1700) SIG_NAME UPI_CPU1_CPU0_P2P2_DN<17>
J 0
(-940 1710);
DISPLAY 0.659574 (-940 1710);
PAINT MONO (-940 1710);
DISPLAY INVISIBLE (-940 1710);
FORCEPROP 1 LASTPIN (-950 1700) BN 17
J 2
(-938 1708);
DISPLAY 0.680851 (-938 1708);
PAINT GREEN (-938 1708);
FORCEPROP 2 LAST CDS_LIB standard
J 0
(-1000 1700);
DISPLAY INVISIBLE (-1000 1700);
FORCEPROP 1 LAST BODY_TYPE PLUMBING
J 2
(-1000 1750);
DISPLAY 0.872340 (-1000 1750);
PAINT GREEN (-1000 1750);
DISPLAY INVISIBLE (-1000 1750);
FORCEPROP 1 LAST HDL_TAP TRUE
J 2
(-1325 1575);
DISPLAY 0.872340 (-1325 1575);
DISPLAY INVISIBLE (-1325 1575);
FORCEPROP 1 LAST PATH I9
J 2
(-998 1700);
DISPLAY 0.872340 (-998 1700);
PAINT GREEN (-998 1700);
DISPLAY INVISIBLE (-998 1700);
FORCEADD TAP..1
(2575 3550);
FORCEPROP 3 LASTPIN (2525 3550) SIG_NAME UPI_CPU0_CPU1_P2P2_DP<5>
J 0
(2535 3560);
DISPLAY 0.659574 (2535 3560);
PAINT MONO (2535 3560);
DISPLAY INVISIBLE (2535 3560);
FORCEPROP 1 LASTPIN (2525 3550) BN 5
J 0
(2513 3558);
DISPLAY 0.680851 (2513 3558);
PAINT GREEN (2513 3558);
FORCEPROP 2 LAST CDS_LIB standard
J 0
(2575 3550);
DISPLAY INVISIBLE (2575 3550);
FORCEPROP 1 LAST BODY_TYPE PLUMBING
J 0
(2575 3600);
DISPLAY 0.872340 (2575 3600);
PAINT GREEN (2575 3600);
DISPLAY INVISIBLE (2575 3600);
FORCEPROP 1 LAST HDL_TAP TRUE
J 0
(2900 3425);
DISPLAY 0.872340 (2900 3425);
DISPLAY INVISIBLE (2900 3425);
FORCEPROP 1 LAST PATH I90
J 0
(2573 3550);
DISPLAY 0.872340 (2573 3550);
PAINT GREEN (2573 3550);
DISPLAY INVISIBLE (2573 3550);
FORCEADD TAP..1
(2575 3450);
FORCEPROP 3 LASTPIN (2525 3450) SIG_NAME UPI_CPU0_CPU1_P2P2_DP<7>
J 0
(2535 3460);
DISPLAY 0.659574 (2535 3460);
PAINT MONO (2535 3460);
DISPLAY INVISIBLE (2535 3460);
FORCEPROP 1 LASTPIN (2525 3450) BN 7
J 0
(2513 3458);
DISPLAY 0.680851 (2513 3458);
PAINT GREEN (2513 3458);
FORCEPROP 2 LAST CDS_LIB standard
J 0
(2575 3450);
PAINT MONO (2575 3450);
DISPLAY INVISIBLE (2575 3450);
FORCEPROP 1 LAST BODY_TYPE PLUMBING
J 0
(2575 3500);
DISPLAY 0.872340 (2575 3500);
PAINT GREEN (2575 3500);
DISPLAY INVISIBLE (2575 3500);
FORCEPROP 1 LAST HDL_TAP TRUE
J 0
(2900 3325);
DISPLAY 0.872340 (2900 3325);
DISPLAY INVISIBLE (2900 3325);
FORCEPROP 1 LAST PATH I91
J 0
(2573 3450);
DISPLAY 0.872340 (2573 3450);
PAINT GREEN (2573 3450);
DISPLAY INVISIBLE (2573 3450);
FORCEADD TAP..1
(2575 3350);
FORCEPROP 3 LASTPIN (2525 3350) SIG_NAME UPI_CPU0_CPU1_P2P2_DP<9>
J 0
(2535 3360);
DISPLAY 0.659574 (2535 3360);
PAINT MONO (2535 3360);
DISPLAY INVISIBLE (2535 3360);
FORCEPROP 1 LASTPIN (2525 3350) BN 9
J 0
(2513 3358);
DISPLAY 0.680851 (2513 3358);
PAINT GREEN (2513 3358);
FORCEPROP 2 LAST CDS_LIB standard
J 0
(2575 3350);
PAINT MONO (2575 3350);
DISPLAY INVISIBLE (2575 3350);
FORCEPROP 1 LAST BODY_TYPE PLUMBING
J 0
(2575 3400);
DISPLAY 0.872340 (2575 3400);
PAINT GREEN (2575 3400);
DISPLAY INVISIBLE (2575 3400);
FORCEPROP 1 LAST HDL_TAP TRUE
J 0
(2900 3225);
DISPLAY 0.872340 (2900 3225);
DISPLAY INVISIBLE (2900 3225);
FORCEPROP 1 LAST PATH I92
J 0
(2573 3350);
DISPLAY 0.872340 (2573 3350);
PAINT GREEN (2573 3350);
DISPLAY INVISIBLE (2573 3350);
FORCEADD TAP..1
(2575 3300);
FORCEPROP 3 LASTPIN (2525 3300) SIG_NAME UPI_CPU0_CPU1_P2P2_DP<10>
J 0
(2535 3310);
DISPLAY 0.659574 (2535 3310);
PAINT MONO (2535 3310);
DISPLAY INVISIBLE (2535 3310);
FORCEPROP 1 LASTPIN (2525 3300) BN 10
J 0
(2513 3308);
DISPLAY 0.680851 (2513 3308);
PAINT GREEN (2513 3308);
FORCEPROP 2 LAST CDS_LIB standard
J 0
(2575 3300);
PAINT MONO (2575 3300);
DISPLAY INVISIBLE (2575 3300);
FORCEPROP 1 LAST BODY_TYPE PLUMBING
J 0
(2575 3350);
DISPLAY 0.872340 (2575 3350);
PAINT GREEN (2575 3350);
DISPLAY INVISIBLE (2575 3350);
FORCEPROP 1 LAST HDL_TAP TRUE
J 0
(2900 3175);
DISPLAY 0.872340 (2900 3175);
DISPLAY INVISIBLE (2900 3175);
FORCEPROP 1 LAST PATH I93
J 0
(2573 3300);
DISPLAY 0.872340 (2573 3300);
PAINT GREEN (2573 3300);
DISPLAY INVISIBLE (2573 3300);
FORCEADD TAP..1
(2575 3400);
FORCEPROP 3 LASTPIN (2525 3400) SIG_NAME UPI_CPU0_CPU1_P2P2_DP<8>
J 0
(2535 3410);
DISPLAY 0.659574 (2535 3410);
PAINT MONO (2535 3410);
DISPLAY INVISIBLE (2535 3410);
FORCEPROP 1 LASTPIN (2525 3400) BN 8
J 0
(2513 3408);
DISPLAY 0.680851 (2513 3408);
PAINT GREEN (2513 3408);
FORCEPROP 2 LAST CDS_LIB standard
J 0
(2575 3400);
PAINT MONO (2575 3400);
DISPLAY INVISIBLE (2575 3400);
FORCEPROP 1 LAST BODY_TYPE PLUMBING
J 0
(2575 3450);
DISPLAY 0.872340 (2575 3450);
PAINT GREEN (2575 3450);
DISPLAY INVISIBLE (2575 3450);
FORCEPROP 1 LAST HDL_TAP TRUE
J 0
(2900 3275);
DISPLAY 0.872340 (2900 3275);
DISPLAY INVISIBLE (2900 3275);
FORCEPROP 1 LAST PATH I94
J 0
(2573 3400);
DISPLAY 0.872340 (2573 3400);
PAINT GREEN (2573 3400);
DISPLAY INVISIBLE (2573 3400);
FORCEADD TAP..1
(2575 3600);
FORCEPROP 3 LASTPIN (2525 3600) SIG_NAME UPI_CPU0_CPU1_P2P2_DP<4>
J 0
(2535 3610);
DISPLAY 0.659574 (2535 3610);
PAINT MONO (2535 3610);
DISPLAY INVISIBLE (2535 3610);
FORCEPROP 1 LASTPIN (2525 3600) BN 4
J 0
(2513 3608);
DISPLAY 0.680851 (2513 3608);
PAINT GREEN (2513 3608);
FORCEPROP 2 LAST CDS_LIB standard
J 0
(2575 3600);
DISPLAY INVISIBLE (2575 3600);
FORCEPROP 1 LAST BODY_TYPE PLUMBING
J 0
(2575 3650);
DISPLAY 0.872340 (2575 3650);
PAINT GREEN (2575 3650);
DISPLAY INVISIBLE (2575 3650);
FORCEPROP 1 LAST HDL_TAP TRUE
J 0
(2900 3475);
DISPLAY 0.872340 (2900 3475);
DISPLAY INVISIBLE (2900 3475);
FORCEPROP 1 LAST PATH I95
J 0
(2573 3600);
DISPLAY 0.872340 (2573 3600);
PAINT GREEN (2573 3600);
DISPLAY INVISIBLE (2573 3600);
FORCEADD TAP..1
(2575 3650);
FORCEPROP 3 LASTPIN (2525 3650) SIG_NAME UPI_CPU0_CPU1_P2P2_DP<3>
J 0
(2535 3660);
DISPLAY 0.659574 (2535 3660);
PAINT MONO (2535 3660);
DISPLAY INVISIBLE (2535 3660);
FORCEPROP 1 LASTPIN (2525 3650) BN 3
J 0
(2513 3658);
DISPLAY 0.680851 (2513 3658);
PAINT GREEN (2513 3658);
FORCEPROP 2 LAST CDS_LIB standard
J 0
(2575 3650);
DISPLAY INVISIBLE (2575 3650);
FORCEPROP 1 LAST BODY_TYPE PLUMBING
J 0
(2575 3700);
DISPLAY 0.872340 (2575 3700);
PAINT GREEN (2575 3700);
DISPLAY INVISIBLE (2575 3700);
FORCEPROP 1 LAST HDL_TAP TRUE
J 0
(2900 3525);
DISPLAY 0.872340 (2900 3525);
DISPLAY INVISIBLE (2900 3525);
FORCEPROP 1 LAST PATH I96
J 0
(2573 3650);
DISPLAY 0.872340 (2573 3650);
PAINT GREEN (2573 3650);
DISPLAY INVISIBLE (2573 3650);
FORCEADD TAP..1
(2575 3700);
FORCEPROP 3 LASTPIN (2525 3700) SIG_NAME UPI_CPU0_CPU1_P2P2_DP<2>
J 0
(2535 3710);
DISPLAY 0.659574 (2535 3710);
PAINT MONO (2535 3710);
DISPLAY INVISIBLE (2535 3710);
FORCEPROP 1 LASTPIN (2525 3700) BN 2
J 0
(2513 3708);
DISPLAY 0.680851 (2513 3708);
PAINT GREEN (2513 3708);
FORCEPROP 2 LAST CDS_LIB standard
J 0
(2575 3700);
DISPLAY INVISIBLE (2575 3700);
FORCEPROP 1 LAST BODY_TYPE PLUMBING
J 0
(2575 3750);
DISPLAY 0.872340 (2575 3750);
PAINT GREEN (2575 3750);
DISPLAY INVISIBLE (2575 3750);
FORCEPROP 1 LAST HDL_TAP TRUE
J 0
(2900 3575);
DISPLAY 0.872340 (2900 3575);
DISPLAY INVISIBLE (2900 3575);
FORCEPROP 1 LAST PATH I97
J 0
(2573 3700);
DISPLAY 0.872340 (2573 3700);
PAINT GREEN (2573 3700);
DISPLAY INVISIBLE (2573 3700);
FORCEADD TAP..1
(2575 3800);
FORCEPROP 3 LASTPIN (2525 3800) SIG_NAME UPI_CPU0_CPU1_P2P2_DP<0>
J 0
(2535 3810);
DISPLAY 0.659574 (2535 3810);
PAINT MONO (2535 3810);
DISPLAY INVISIBLE (2535 3810);
FORCEPROP 1 LASTPIN (2525 3800) BN 0
J 0
(2513 3808);
DISPLAY 0.680851 (2513 3808);
PAINT GREEN (2513 3808);
FORCEPROP 2 LAST CDS_LIB standard
J 0
(2575 3800);
DISPLAY INVISIBLE (2575 3800);
FORCEPROP 1 LAST BODY_TYPE PLUMBING
J 0
(2575 3850);
DISPLAY 0.872340 (2575 3850);
PAINT GREEN (2575 3850);
DISPLAY INVISIBLE (2575 3850);
FORCEPROP 1 LAST HDL_TAP TRUE
J 0
(2900 3675);
DISPLAY 0.872340 (2900 3675);
DISPLAY INVISIBLE (2900 3675);
FORCEPROP 1 LAST PATH I98
J 0
(2573 3800);
DISPLAY 0.872340 (2573 3800);
PAINT GREEN (2573 3800);
DISPLAY INVISIBLE (2573 3800);
FORCEADD TAP..1
(2575 3750);
FORCEPROP 3 LASTPIN (2525 3750) SIG_NAME UPI_CPU0_CPU1_P2P2_DP<1>
J 0
(2535 3760);
DISPLAY 0.659574 (2535 3760);
PAINT MONO (2535 3760);
DISPLAY INVISIBLE (2535 3760);
FORCEPROP 1 LASTPIN (2525 3750) BN 1
J 0
(2513 3758);
DISPLAY 0.680851 (2513 3758);
PAINT GREEN (2513 3758);
FORCEPROP 2 LAST CDS_LIB standard
J 0
(2575 3750);
DISPLAY INVISIBLE (2575 3750);
FORCEPROP 1 LAST BODY_TYPE PLUMBING
J 0
(2575 3800);
DISPLAY 0.872340 (2575 3800);
PAINT GREEN (2575 3800);
DISPLAY INVISIBLE (2575 3800);
FORCEPROP 1 LAST HDL_TAP TRUE
J 0
(2900 3625);
DISPLAY 0.872340 (2900 3625);
DISPLAY INVISIBLE (2900 3625);
FORCEPROP 1 LAST PATH I99
J 0
(2573 3750);
DISPLAY 0.872340 (2573 3750);
PAINT GREEN (2573 3750);
DISPLAY INVISIBLE (2573 3750);
FORCEADD DESIGN_NOTE..1
(3675 3350);
FORCEPROP 0 LAST S2 2.LANE REVERSAL
J 0
(3475 3100);
DISPLAY 1.021277 (3475 3100);
PAINT SKYBLUE (3475 3100);
FORCEPROP 0 LAST S1 1.DP/DN SWAP
J 0
(3475 3200);
DISPLAY 1.021277 (3475 3200);
PAINT SKYBLUE (3475 3200);
FORCEPROP 2 LAST CDS_LIB logical_power
J 0
(3675 3350);
DISPLAY INVISIBLE (3675 3350);
FORCEPROP 1 LAST COMMENT_BODY TRUE
J 0
(3700 3450);
DISPLAY 0.978723 (3700 3450);
DISPLAY INVISIBLE (3700 3450);
FORCEADD DESIGN_NOTE..1
(-2250 3350);
FORCEPROP 0 LAST S2 2.LANE REVERSAL
J 0
(-2450 3100);
DISPLAY 1.021277 (-2450 3100);
PAINT SKYBLUE (-2450 3100);
FORCEPROP 0 LAST S1 1.DP/DN SWAP
J 0
(-2450 3200);
DISPLAY 1.021277 (-2450 3200);
PAINT SKYBLUE (-2450 3200);
FORCEPROP 2 LAST CDS_LIB logical_power
J 0
(-2250 3350);
DISPLAY INVISIBLE (-2250 3350);
FORCEPROP 1 LAST COMMENT_BODY TRUE
J 0
(-2225 3450);
DISPLAY 0.978723 (-2225 3450);
DISPLAY INVISIBLE (-2225 3450);
FORCEADD QUANTA_TITLE_BLOCK_C..1
(5500 -1700);
FORCEPROP 0 LAST CDS_CON_LAST_MODIFIED Fri Aug 25 14:00:18 2023
J 0
(3615 -1685);
PAINT MONO (3615 -1685);
DISPLAY INVISIBLE (3615 -1685);
FORCEPROP 1 LAST CUSTOM_TXT_CDS <CON_LAST_MODIFIED>
J 0
(3615 -1685);
DISPLAY 0.978723 (3615 -1685);
FORCEPROP 2 LAST CUSTOM_TXT_CDS <XR_PAGE_TITLE>
J 0
(-2390 3550);
DISPLAY 0.638298 (-2390 3550);
PAINT PINK (-2390 3550);
DISPLAY INVISIBLE (-2390 3550);
FORCEPROP 2 LAST CUSTOM_TXT_CDS <Q_NUMBER>
J 0
(4097 -1597);
DISPLAY 1.212766 (4097 -1597);
FORCEPROP 1 LAST CUSTOM_TXT_CDS <NAME_2>
J 0
(2325 -1650);
FORCEPROP 1 LAST CUSTOM_TXT_CDS <NAME_1>
J 0
(2325 -1525);
FORCEPROP 1 LAST CUSTOM_TXT_CDS <Q_PROJ>
J 0
(3118 -1598);
DISPLAY 1.212766 (3118 -1598);
FORCEPROP 1 LAST CUSTOM_TXT_CDS <Q_REV>
J 0
(5316 -1597);
DISPLAY 1.212766 (5316 -1597);
FORCEPROP 1 LAST CUSTOM_TXT_CDS <CON_PAGE_NUM> OF <CON_TOTAL_PAGES>
J 0
(5054 -1682);
DISPLAY 0.978723 (5054 -1682);
FORCEPROP 1 LAST Q_TITLE SPR CPU0 - UPI2 (22 OF 30)
J 0
(-3866 -1674);
DISPLAY 1.957447 (-3866 -1674);
PAINT GREEN (-3866 -1674);
FORCEPROP 1 LAST Q_DEPT 
J 1
(1737 -1651);
DISPLAY 1.957447 (1737 -1651);
PAINT GREEN (1737 -1651);
FORCEPROP 2 LAST CDS_LIB pure_quanta
J 0
(5500 -1700);
PAINT MONO (5500 -1700);
DISPLAY INVISIBLE (5500 -1700);
FORCEPROP 1 LAST CDS_LMAN_SYM_OUTLINE -9475,6775,100,-125
J 0
(5500 -1700);
DISPLAY 0.468085 (5500 -1700);
PAINT GREEN (5500 -1700);
DISPLAY INVISIBLE (5500 -1700);
FORCEPROP 2 LAST PAGE_BORDER TRUE
J 0
(-2390 3550);
DISPLAY 0.638298 (-2390 3550);
PAINT PINK (-2390 3550);
DISPLAY INVISIBLE (-2390 3550);
FORCEPROP 2 LAST CDS_XR_PAGE_TITLE CR-34 : @S9S_MB_2U_LIB.S9S_MB_2U(SCH_1):PAGE34
J 0
(-2390 3550);
DISPLAY 0.638298 (-2390 3550);
PAINT PINK (-2390 3550);
DISPLAY INVISIBLE (-2390 3550);
FORCEPROP 1 LAST COMMENT_BODY TRUE
J 0
(5512 -1713);
DISPLAY 0.978723 (5512 -1713);
PAINT GREEN (5512 -1713);
DISPLAY INVISIBLE (5512 -1713);
WIRE 17 -1 (2625 2675)(2625 2725);
WIRE 17 -1 (2625 2725)(2625 2775);
WIRE 17 -1 (2625 2775)(2625 2825);
WIRE 17 -1 (2625 2825)(2625 2875);
WIRE 17 -1 (2625 2875)(2625 2925);
WIRE 17 -1 (2625 2925)(2625 2975);
WIRE 17 -1 (2625 2975)(2625 3025);
WIRE 17 -1 (2625 3025)(2625 3075);
WIRE 17 -1 (2625 3075)(2625 3125);
WIRE 17 -1 (2625 3125)(2625 3175);
WIRE 17 -1 (2625 3175)(2625 3225);
WIRE 17 -1 (2625 3225)(2625 3275);
WIRE 17 -1 (2625 3275)(2625 3325);
WIRE 17 -1 (2625 3325)(2625 3375);
WIRE 17 -1 (2625 3375)(2625 3425);
WIRE 17 -1 (2625 3425)(2625 3475);
WIRE 17 -1 (2625 3475)(2625 3525);
WIRE 17 -1 (2625 3525)(2625 3575);
WIRE 17 -1 (2625 3575)(2625 3625);
WIRE 17 -1 (2625 3625)(2625 3675);
WIRE 17 -1 (2625 3675)(2625 3725);
WIRE 17 -1 (2625 3725)(2625 3775);
WIRE 17 -1 (2625 3775)(2625 3825);
WIRE 17 -1 (2625 3825)(3725 3825);
FORCEPROP 2 LAST SIG_NAME UPI_CPU0_CPU1_P2P2_DP<23:0>
J 0
(2765 3835);
DISPLAY 0.680851 (2765 3835);
PAINT WHITE (2765 3835);
WIRE 17 -1 (2625 1425)(2625 1475);
WIRE 17 -1 (2625 1475)(2625 1525);
WIRE 17 -1 (2625 1525)(2625 1575);
WIRE 17 -1 (2625 1575)(2625 1625);
WIRE 17 -1 (2625 1625)(2625 1675);
WIRE 17 -1 (2625 1675)(2625 1725);
WIRE 17 -1 (2625 1725)(2625 1775);
WIRE 17 -1 (2625 1775)(2625 1825);
WIRE 17 -1 (2625 1875)(2625 1825);
WIRE 17 -1 (2625 1875)(2625 1925);
WIRE 17 -1 (2625 1925)(2625 1975);
WIRE 17 -1 (2625 1975)(2625 2025);
WIRE 17 -1 (2625 2025)(2625 2075);
WIRE 17 -1 (2625 2075)(2625 2125);
WIRE 17 -1 (2625 2125)(2625 2175);
WIRE 17 -1 (2625 2175)(2625 2225);
WIRE 17 -1 (2625 2225)(2625 2275);
WIRE 17 -1 (2625 2275)(2625 2325);
WIRE 17 -1 (2625 2325)(2625 2375);
WIRE 17 -1 (2625 2375)(2625 2425);
WIRE 17 -1 (2625 2425)(2625 2475);
WIRE 17 -1 (2625 2475)(2625 2525);
WIRE 17 -1 (2625 2525)(2625 2575);
WIRE 17 -1 (2625 2575)(3725 2575);
FORCEPROP 2 LAST SIG_NAME UPI_CPU0_CPU1_P2P2_DN<23:0>
J 0
(2765 2585);
DISPLAY 0.680851 (2765 2585);
PAINT WHITE (2765 2585);
WIRE 17 -1 (-850 2675)(-850 2775);
WIRE 17 -1 (-850 2675)(-850 2575);
WIRE 17 -1 (-850 2775)(-850 2825);
WIRE 17 -1 (-850 2825)(-850 2875);
WIRE 17 -1 (-850 2575)(-850 2475);
WIRE 17 -1 (-850 2475)(-850 2425);
WIRE 17 -1 (-850 2875)(-850 2925);
WIRE 17 -1 (-850 2925)(-850 2975);
WIRE 17 -1 (-850 2425)(-850 2375);
WIRE 17 -1 (-850 2375)(-850 2225);
WIRE 17 -1 (-850 2975)(-850 3175);
WIRE 17 -1 (-850 3175)(-850 3325);
WIRE 17 -1 (-850 2225)(-850 2175);
WIRE 17 -1 (-850 2175)(-850 2025);
WIRE 17 -1 (-850 3325)(-850 3375);
WIRE 17 -1 (-850 3375)(-850 3525);
WIRE 17 -1 (-850 2025)(-850 1975);
WIRE 17 -1 (-850 1975)(-850 1875);
WIRE 17 -1 (-850 3525)(-850 3575);
WIRE 17 -1 (-850 3575)(-850 3775);
WIRE 17 -1 (-850 1875)(-850 1825);
WIRE 17 -1 (-850 1825)(-850 1775);
WIRE 17 -1 (-850 3775)(-850 3925);
WIRE 17 -1 (-2250 3925)(-850 3925);
FORCEPROP 2 LAST SIG_NAME UPI_CPU1_CPU0_P2P2_DP<23:0>
J 0
(-2135 3935);
DISPLAY 0.680851 (-2135 3935);
PAINT WHITE (-2135 3935);
WIRE 17 -1 (-1050 2600)(-1050 2725);
WIRE 17 -1 (-1050 2525)(-1050 2600);
WIRE 17 -1 (-2250 2600)(-1050 2600);
FORCEPROP 2 LAST SIG_NAME UPI_CPU1_CPU0_P2P2_DN<23:0>
J 0
(-2135 2610);
DISPLAY 0.680851 (-2135 2610);
PAINT WHITE (-2135 2610);
WIRE 17 -1 (-1050 3025)(-1050 2725);
WIRE 17 -1 (-1050 3025)(-1050 3075);
WIRE 17 -1 (-1050 3075)(-1050 3125);
WIRE 17 -1 (-1050 3125)(-1050 3225);
WIRE 17 -1 (-1050 3225)(-1050 3275);
WIRE 17 -1 (-1050 3275)(-1050 3425);
WIRE 17 -1 (-1050 3425)(-1050 3475);
WIRE 17 -1 (-1050 3475)(-1050 3625);
WIRE 17 -1 (-1050 3625)(-1050 3675);
WIRE 17 -1 (-1050 3675)(-1050 3725);
WIRE 17 -1 (-1050 3725)(-1050 3825);
WIRE 17 -1 (-1050 1525)(-1050 1425);
WIRE 17 -1 (-1050 1575)(-1050 1525);
WIRE 17 -1 (-1050 1575)(-1050 1625);
WIRE 17 -1 (-1050 1625)(-1050 1675);
WIRE 17 -1 (-1050 1675)(-1050 1725);
WIRE 17 -1 (-1050 1925)(-1050 1725);
WIRE 17 -1 (-1050 2075)(-1050 1925);
WIRE 17 -1 (-1050 2075)(-1050 2125);
WIRE 17 -1 (-1050 2275)(-1050 2125);
WIRE 17 -1 (-1050 2275)(-1050 2325);
WIRE 17 -1 (-1050 2525)(-1050 2325);
WIRE 17 -1 (-850 1475)(-850 1775);
WIRE 16 -1 (-750 2550)(-300 2550);
WIRE 16 -1 (-950 2500)(-300 2500);
WIRE 16 -1 (-750 2450)(-300 2450);
WIRE 16 -1 (-750 2400)(-300 2400);
WIRE 16 -1 (-750 2350)(-300 2350);
WIRE 16 -1 (-950 2300)(-300 2300);
WIRE 16 -1 (-950 2250)(-300 2250);
WIRE 16 -1 (-750 2200)(-300 2200);
WIRE 16 -1 (-750 2150)(-300 2150);
WIRE 16 -1 (-950 2100)(-300 2100);
WIRE 16 -1 (-950 2050)(-300 2050);
WIRE 16 -1 (-750 2000)(-300 2000);
WIRE 16 -1 (-750 1950)(-300 1950);
WIRE 16 -1 (-950 1900)(-300 1900);
WIRE 16 -1 (-750 1850)(-300 1850);
WIRE 16 -1 (-750 1800)(-300 1800);
WIRE 16 -1 (-750 1750)(-300 1750);
WIRE 16 -1 (-950 1700)(-300 1700);
WIRE 16 -1 (-950 1650)(-300 1650);
WIRE 16 -1 (-950 1600)(-300 1600);
WIRE 16 -1 (-950 1550)(-300 1550);
WIRE 16 -1 (-950 1500)(-300 1500);
FORCEPROP 0 LAST $PNN UPI_CPU1_CPU0_P2P2_DP<21>
J 0
(-850 1500);
DISPLAY INVISIBLE (-850 1500);
WIRE 16 -1 (-750 1450)(-300 1450);
WIRE 16 -1 (-950 1400)(-300 1400);
WIRE 16 -1 (-300 3800)(-950 3800);
WIRE 16 -1 (-750 3750)(-300 3750);
WIRE 16 -1 (-300 3700)(-950 3700);
WIRE 16 -1 (-300 3650)(-950 3650);
WIRE 16 -1 (-300 3600)(-950 3600);
WIRE 16 -1 (-750 3550)(-300 3550);
WIRE 16 -1 (-750 3500)(-300 3500);
WIRE 16 -1 (-300 3450)(-950 3450);
WIRE 16 -1 (-950 3400)(-300 3400);
WIRE 16 -1 (-750 3350)(-300 3350);
WIRE 16 -1 (-750 3300)(-300 3300);
WIRE 16 -1 (-950 3250)(-300 3250);
WIRE 16 -1 (-950 3200)(-300 3200);
WIRE 16 -1 (-750 3150)(-300 3150);
WIRE 16 -1 (-950 3100)(-300 3100);
WIRE 16 -1 (-950 3050)(-300 3050);
WIRE 16 -1 (-300 3000)(-950 3000);
WIRE 16 -1 (-750 2950)(-300 2950);
WIRE 16 -1 (-750 2900)(-300 2900);
WIRE 16 -1 (-750 2850)(-300 2850);
WIRE 16 -1 (-750 2800)(-300 2800);
WIRE 16 -1 (-750 2750)(-300 2750);
WIRE 16 -1 (-300 2700)(-950 2700);
WIRE 16 -1 (-750 2650)(-300 2650);
WIRE 16 -1 (2100 2550)(2525 2550);
WIRE 16 -1 (2100 2500)(2525 2500);
WIRE 16 -1 (2100 2450)(2525 2450);
WIRE 16 -1 (2100 2400)(2525 2400);
WIRE 16 -1 (2100 2350)(2525 2350);
WIRE 16 -1 (2100 2300)(2525 2300);
WIRE 16 -1 (2100 2250)(2525 2250);
WIRE 16 -1 (2100 2200)(2525 2200);
WIRE 16 -1 (2100 2150)(2525 2150);
WIRE 16 -1 (2100 2100)(2525 2100);
WIRE 16 -1 (2100 2050)(2525 2050);
WIRE 16 -1 (2100 2000)(2525 2000);
WIRE 16 -1 (2100 1950)(2525 1950);
WIRE 16 -1 (2100 1900)(2525 1900);
WIRE 16 -1 (2100 1850)(2525 1850);
WIRE 16 -1 (2100 1800)(2525 1800);
WIRE 16 -1 (2100 1750)(2525 1750);
WIRE 16 -1 (2100 1700)(2525 1700);
WIRE 16 -1 (2100 1650)(2525 1650);
WIRE 16 -1 (2100 1600)(2525 1600);
WIRE 16 -1 (2100 1550)(2525 1550);
WIRE 16 -1 (2100 1500)(2525 1500);
WIRE 16 -1 (2100 1450)(2525 1450);
WIRE 16 -1 (2100 1400)(2525 1400);
WIRE 16 -1 (2100 3800)(2525 3800);
WIRE 16 -1 (2100 3750)(2525 3750);
WIRE 16 -1 (2100 3700)(2525 3700);
WIRE 16 -1 (2100 3650)(2525 3650);
WIRE 16 -1 (2100 3600)(2525 3600);
WIRE 16 -1 (2100 3550)(2525 3550);
WIRE 16 -1 (2100 3500)(2525 3500);
WIRE 16 -1 (2100 3450)(2525 3450);
WIRE 16 -1 (2100 3400)(2525 3400);
WIRE 16 -1 (2100 3350)(2525 3350);
WIRE 16 -1 (2100 3300)(2525 3300);
WIRE 16 -1 (2100 3250)(2525 3250);
WIRE 16 -1 (2100 3200)(2525 3200);
WIRE 16 -1 (2100 3150)(2525 3150);
WIRE 16 -1 (2100 3100)(2525 3100);
WIRE 16 -1 (2100 3050)(2525 3050);
WIRE 16 -1 (2100 3000)(2525 3000);
WIRE 16 -1 (2100 2950)(2525 2950);
WIRE 16 -1 (2100 2900)(2525 2900);
WIRE 16 -1 (2100 2850)(2525 2850);
WIRE 16 -1 (2100 2800)(2525 2800);
WIRE 16 -1 (2100 2750)(2525 2750);
WIRE 16 -1 (2100 2700)(2525 2700);
WIRE 16 -1 (2100 2650)(2525 2650);
DOT 1 (-1050 2600);
QUIT
